G04 ================== begin FILE IDENTIFICATION RECORD ==================*
G04 Layout Name:  9048_F0T_Management_Board_D_brd_V04_1213_1625.brd*
G04 Film Name:    smt*
G04 File Format:  Gerber RS274X*
G04 File Origin:  Cadence Allegro 17.2-S081*
G04 Origin Date:  Tue Dec 13 16:31:10 2022*
G04 *
G04 Layer:  DRAWING FORMAT/TITLE_BLOCK_A*
G04 Layer:  DRAWING FORMAT/TITLE_BLOCK*
G04 Layer:  VIA CLASS/SOLDERMASK_TOP*
G04 Layer:  PIN/SOLDERMASK_TOP*
G04 Layer:  PACKAGE GEOMETRY/SOLDERMASK_TOP*
G04 Layer:  MANUFACTURING/PHOTOPLOT_OUTLINE*
G04 Layer:  DRAWING FORMAT/TITLE_DATA_SMT*
G04 Layer:  BOARD GEOMETRY/SOLDERMASK_TOP*
G04 *
G04 Offset:    (0.00 0.00)*
G04 Mirror:    No*
G04 Mode:      Positive*
G04 Rotation:  0*
G04 FullContactRelief:  No*
G04 UndefLineWidth:     6.00*
G04 ================== end FILE IDENTIFICATION RECORD ====================*
%FSLAX25Y25*MOIN*%
%IR0*IPPOS*OFA0.00000B0.00000*MIA0B0*SFA1.00000B1.00000*%
%AMMACRO32*
4,1,5,.01972,-.00791,
-.01264,-.00791,
-.01972,-.00083,
-.01972,.00791,
.01972,.00791,
.01972,-.00791,
0.0*
%
%ADD32MACRO32*%
%AMMACRO29*
4,1,32,-.01575,.06201,
-.01575,.0502,
.00197,.0502,
.00197,.04035,
-.01575,.04035,
-.01575,.03248,
.00197,.03248,
.00197,.02461,
-.01575,.02461,
-.01575,.01673,
.00197,.01673,
.00197,.00886,
-.01575,.00886,
-.01575,.00098,
.00197,.00098,
.00197,-.00689,
-.01575,-.00689,
-.01575,-.01476,
.00197,-.01476,
.00197,-.02264,
-.01575,-.02264,
-.01575,-.03051,
.00197,-.03051,
.00197,-.03839,
-.01575,-.03839,
-.01575,-.04626,
.00197,-.04626,
.00197,-.05413,
-.01575,-.05413,
-.01575,-.06201,
.01575,-.06201,
.01575,.06201,
-.01575,.06201,
0.0*
%
%ADD29MACRO29*%
%ADD50R,.113X.044*%
%ADD61R,.053X.114*%
%ADD112R,.235X.06*%
%ADD62C,.02*%
%ADD44C,.03*%
%ADD119R,.109X.073*%
%ADD120C,.061*%
%ADD96R,.073X.109*%
%ADD66C,.052*%
%ADD11C,.034*%
%ADD46C,.065*%
%ADD13C,.056*%
%ADD94C,.048*%
%ADD10C,.085*%
%AMMACRO121*
4,1,8,.08,-.0445,
-.08,-.0445,
-.08,.0445,
-.0216,.0445,
-.0216,.0165,
.0216,.0165,
.0216,.0445,
.08,.0445,
.08,-.0445,
0.0*
%
%ADD121MACRO121*%
%ADD116C,.0185*%
%ADD60C,.068*%
%ADD57R,.052X.052*%
%ADD97C,.087*%
%ADD104R,.036X.036*%
%ADD124C,.0395*%
%ADD47R,.065X.065*%
%ADD42R,.134X.0888*%
%ADD12R,.083X.083*%
%ADD98R,.048X.048*%
%ADD125C,.0785*%
%AMMACRO53*
4,1,5,.01578,-.00692,
-.01067,-.00692,
-.01578,-.00181,
-.01578,.00692,
.01578,.00692,
.01578,-.00692,
0.0*
%
%ADD53MACRO53*%
%AMMACRO41*
4,1,5,-.00692,-.01578,
-.00692,.01067,
-.00181,.01578,
.00692,.01578,
.00692,-.01578,
-.00692,-.01578,
0.0*
%
%ADD41MACRO41*%
%AMMACRO19*
4,1,28,-.00589,-.01192,
-.006913,-.011842,
-.007907,-.011587,
-.008842,-.011163,
-.009688,-.010584,
-.010422,-.009866,
-.011019,-.009032,
-.011463,-.008107,
-.011739,-.007119,
-.01184,-.006097,
-.01184,-.00603,
-.01184,.00148,
-.00948,.00148,
-.00948,.01191,
.00948,.01191,
.00948,.00148,
.01184,.00148,
.01184,-.00603,
.011751,-.007052,
.011486,-.008044,
.011053,-.008974,
.010465,-.009815,
.00974,-.010541,
.0089,-.01113,
.00797,-.011564,
.006979,-.01183,
.005957,-.01192,
.00589,-.01192,
-.00589,-.01192,
0.0*
%
%ADD19MACRO19*%
%AMMACRO20*
4,1,28,-.01192,.00589,
-.011842,.006913,
-.011587,.007907,
-.011163,.008842,
-.010584,.009688,
-.009866,.010422,
-.009032,.011019,
-.008107,.011463,
-.007119,.011739,
-.006097,.01184,
-.00603,.01184,
.00148,.01184,
.00148,.00948,
.01191,.00948,
.01191,-.00948,
.00148,-.00948,
.00148,-.01184,
-.00603,-.01184,
-.007052,-.011751,
-.008044,-.011486,
-.008974,-.011053,
-.009815,-.010465,
-.010541,-.00974,
-.01113,-.0089,
-.011564,-.00797,
-.01183,-.006979,
-.01192,-.005957,
-.01192,-.00589,
-.01192,.00589,
0.0*
%
%ADD20MACRO20*%
%AMMACRO52*
4,1,5,.01578,-.00692,
-.01578,-.00692,
-.01578,.00181,
-.01067,.00692,
.01578,.00692,
.01578,-.00692,
0.0*
%
%ADD52MACRO52*%
%AMMACRO54*
4,1,5,-.00692,-.01578,
-.00692,.01578,
.00181,.01578,
.00692,.01067,
.00692,-.01578,
-.00692,-.01578,
0.0*
%
%ADD54MACRO54*%
%AMMACRO18*
4,1,28,.0059,.01191,
.006923,.01183,
.007916,.011573,
.00885,.011148,
.009696,.010567,
.010428,.009849,
.011024,.009013,
.011466,.008088,
.011741,.007099,
.01184,.006078,
.01184,.00602,
.01184,-.00149,
.00948,-.00149,
.00948,-.01192,
-.00948,-.01192,
-.00948,-.00149,
-.01184,-.00149,
-.01184,.00602,
-.011751,.007042,
-.011486,.008033,
-.011053,.008964,
-.010465,.009805,
-.00974,.010531,
-.0089,.01112,
-.007971,.011554,
-.00698,.01182,
-.005958,.01191,
-.0059,.01191,
.0059,.01191,
0.0*
%
%ADD18MACRO18*%
%AMMACRO28*
4,1,28,.01191,-.0059,
.01183,-.006923,
.011573,-.007916,
.011148,-.00885,
.010567,-.009696,
.009849,-.010428,
.009013,-.011024,
.008088,-.011466,
.007099,-.011741,
.006078,-.01184,
.00602,-.01184,
-.00149,-.01184,
-.00149,-.00948,
-.01192,-.00948,
-.01192,.00948,
-.00149,.00948,
-.00149,.01184,
.00602,.01184,
.007042,.011751,
.008033,.011486,
.008964,.011053,
.009805,.010465,
.010531,.00974,
.01112,.0089,
.011554,.007971,
.01182,.00698,
.01191,.005958,
.01191,.0059,
.01191,-.0059,
0.0*
%
%ADD28MACRO28*%
%ADD71R,.02X.04*%
%ADD85R,.025X.01*%
%ADD63R,.024X.02*%
%ADD101R,.01X.025*%
%ADD81R,.024X.021*%
%ADD91R,.04X.015*%
%ADD69R,.032X.014*%
%ADD49R,.021X.024*%
%ADD39R,.014X.04*%
%ADD118R,.015X.04*%
%ADD67R,.014X.032*%
%ADD56R,.022X.024*%
%ADD33R,.036X.011*%
%ADD27R,.134X.134*%
%ADD92R,.021X.071*%
%ADD72R,.015X.032*%
%ADD109R,.05X.017*%
%ADD108R,.038X.02*%
%ADD79R,.04X.018*%
%ADD78R,.044X.032*%
%ADD45R,.028X.021*%
%ADD123R,.016X.024*%
%ADD102R,.018X.04*%
%ADD86R,.021X.028*%
%ADD84R,.023X.018*%
%ADD75R,.06X.044*%
%ADD58R,.017X.05*%
%ADD51R,.032X.044*%
%ADD35R,.036X.032*%
%ADD103R,.056X.022*%
%ADD99R,.018X.023*%
%ADD73R,.032X.036*%
%ADD68R,.014X.063*%
%ADD111C,.241*%
%ADD110R,.05X.038*%
%ADD106R,.042X.028*%
%ADD93R,.024X.063*%
%ADD82R,.028X.032*%
%ADD80R,.058X.03*%
%ADD30R,.036X.016*%
%ADD24R,.05X.073*%
%ADD117R,.053X.018*%
%ADD107R,.038X.024*%
%ADD40R,.014X.056*%
%ADD15C,.242*%
%ADD14C,.26*%
%ADD115R,.028X.026*%
%ADD105R,.05X.066*%
%ADD89R,.027X.018*%
%ADD87C,.135*%
%ADD83R,.026X.036*%
%ADD48R,.019X.044*%
%ADD34R,.044X.054*%
%ADD114R,.044X.019*%
%ADD100R,.018X.027*%
%ADD95R,.075X.052*%
%ADD76O,.256X.319*%
%ADD31R,.016X.083*%
%ADD26C,.145*%
%ADD16C,.118*%
%ADD77C,.182*%
%ADD74R,.015X.067*%
%ADD64R,.019X.072*%
%ADD90R,.028X.046*%
%ADD88R,.065X.028*%
%ADD25R,.063X.083*%
%ADD59R,.018X.048*%
%AMMACRO122*
4,1,8,-.08,.0445,
.08,.0445,
.08,-.0445,
.0216,-.0445,
.0216,-.0165,
-.0216,-.0165,
-.0216,-.0445,
-.08,-.0445,
-.08,.0445,
0.0*
%
%ADD122MACRO122*%
%ADD113R,.069X.028*%
%ADD17R,.058X.048*%
%ADD70R,.048X.058*%
%ADD65R,.019X.088*%
%AMMACRO55*
4,1,5,.00692,.01578,
.00692,-.01067,
.00181,-.01578,
-.00692,-.01578,
-.00692,.01578,
.00692,.01578,
0.0*
%
%ADD55MACRO55*%
%AMMACRO38*
4,1,5,-.01578,.00692,
.01067,.00692,
.01578,.00181,
.01578,-.00692,
-.01578,-.00692,
-.01578,.00692,
0.0*
%
%ADD38MACRO38*%
%AMMACRO36*
4,1,28,.01192,-.00589,
.011842,-.006913,
.011587,-.007907,
.011163,-.008842,
.010584,-.009688,
.009866,-.010422,
.009032,-.011019,
.008107,-.011463,
.007119,-.011739,
.006097,-.01184,
.00603,-.01184,
-.00148,-.01184,
-.00148,-.00948,
-.01191,-.00948,
-.01191,.00948,
-.00148,.00948,
-.00148,.01184,
.00603,.01184,
.007052,.011751,
.008044,.011486,
.008974,.011053,
.009815,.010465,
.010541,.00974,
.01113,.0089,
.011564,.00797,
.01183,.006979,
.01192,.005957,
.01192,.00589,
.01192,-.00589,
0.0*
%
%ADD36MACRO36*%
%AMMACRO23*
4,1,28,.00589,.01192,
.006913,.011842,
.007907,.011587,
.008842,.011163,
.009688,.010584,
.010422,.009866,
.011019,.009032,
.011463,.008107,
.011739,.007119,
.01184,.006097,
.01184,.00603,
.01184,-.00148,
.00948,-.00148,
.00948,-.01191,
-.00948,-.01191,
-.00948,-.00148,
-.01184,-.00148,
-.01184,.00603,
-.011751,.007052,
-.011486,.008044,
-.011053,.008974,
-.010465,.009815,
-.00974,.010541,
-.0089,.01113,
-.00797,.011564,
-.006979,.01183,
-.005957,.01192,
-.00589,.01192,
.00589,.01192,
0.0*
%
%ADD23MACRO23*%
%AMMACRO43*
4,1,5,.00692,.01578,
.00692,-.01578,
-.00181,-.01578,
-.00692,-.01067,
-.00692,.01578,
.00692,.01578,
0.0*
%
%ADD43MACRO43*%
%AMMACRO37*
4,1,5,-.01578,.00692,
.01578,.00692,
.01578,-.00181,
.01067,-.00692,
-.01578,-.00692,
-.01578,.00692,
0.0*
%
%ADD37MACRO37*%
%AMMACRO22*
4,1,28,-.01191,.0059,
-.01183,.006923,
-.011573,.007916,
-.011148,.00885,
-.010567,.009696,
-.009849,.010428,
-.009013,.011024,
-.008088,.011466,
-.007099,.011741,
-.006078,.01184,
-.00602,.01184,
.00149,.01184,
.00149,.00948,
.01192,.00948,
.01192,-.00948,
.00149,-.00948,
.00149,-.01184,
-.00602,-.01184,
-.007042,-.011751,
-.008033,-.011486,
-.008964,-.011053,
-.009805,-.010465,
-.010531,-.00974,
-.01112,-.0089,
-.011554,-.007971,
-.01182,-.00698,
-.01191,-.005958,
-.01191,-.0059,
-.01191,.0059,
0.0*
%
%ADD22MACRO22*%
%AMMACRO21*
4,1,28,-.0059,-.01191,
-.006923,-.01183,
-.007916,-.011573,
-.00885,-.011148,
-.009696,-.010567,
-.010428,-.009849,
-.011024,-.009013,
-.011466,-.008088,
-.011741,-.007099,
-.01184,-.006078,
-.01184,-.00602,
-.01184,.00149,
-.00948,.00149,
-.00948,.01192,
.00948,.01192,
.00948,.00149,
.01184,.00149,
.01184,-.00602,
.011751,-.007042,
.011486,-.008033,
.011053,-.008964,
.010465,-.009805,
.00974,-.010531,
.0089,-.01112,
.007971,-.011554,
.00698,-.01182,
.005958,-.01191,
.0059,-.01191,
-.0059,-.01191,
0.0*
%
%ADD21MACRO21*%
%ADD126C,.006*%
G75*
%LPD*%
G75*
G36*
G01X16370Y71500D02*
G03I-5900J0D01*
G37*
G36*
G01X18000Y438790D02*
G03I-5900J0D01*
G37*
G36*
G01X55177Y474015D02*
X52224Y471063D01*
Y461978D01*
X124508D01*
Y471063D01*
X121555Y474015D01*
X55177D01*
G37*
G36*
G01X109900Y157600D02*
G03I-5900J0D01*
G37*
G36*
G01X138287Y474015D02*
X135335Y471063D01*
Y461978D01*
X174547D01*
Y471063D01*
X171595Y474015D01*
X138287D01*
G37*
G36*
G01X184783D02*
X181831Y471063D01*
Y461978D01*
X254075D01*
Y471063D01*
X251122Y474015D01*
X184783D01*
G37*
G36*
G01X275500Y337700D02*
G03I-5900J0D01*
G37*
G36*
G01X265886Y474015D02*
X262933Y471063D01*
Y461978D01*
X302126D01*
Y471063D01*
X299173Y474015D01*
X265886D01*
G37*
G36*
G01X316700Y42000D02*
G03I-5900J0D01*
G37*
G36*
G01X329100Y451500D02*
G03I-5900J0D01*
G37*
G54D100*
X166719Y70222D03*
G54D110*
X228832Y107236D03*
X220564D03*
Y113732D03*
X228832D03*
G54D101*
X162782Y73126D03*
X164751D03*
Y70074D03*
X162782D03*
X168687Y73126D03*
X170656D03*
Y70074D03*
X168687D03*
G54D111*
X236220Y424016D03*
X301181D03*
G54D102*
X163334Y90590D03*
Y83898D03*
X159988D03*
Y90590D03*
X172758D03*
Y83898D03*
X169412D03*
Y90590D03*
G54D120*
X372604Y-455313D03*
Y-430313D03*
X372664Y-223791D03*
Y-198791D03*
X372576Y-177041D03*
Y-152041D03*
X372664Y4481D03*
Y29481D03*
X372604Y51231D03*
Y76231D03*
X372664Y373753D03*
Y398753D03*
X393692Y-481375D03*
X382604Y-455313D03*
X393692Y-456375D03*
X382604Y-430313D03*
X382664Y-223791D03*
Y-198791D03*
X382576Y-177041D03*
Y-152041D03*
X393780Y-128853D03*
Y-103853D03*
X393750Y-82222D03*
Y-57222D03*
X382664Y4481D03*
Y29481D03*
X382604Y51231D03*
Y76231D03*
X393750Y200538D03*
Y225538D03*
Y247050D03*
Y272050D03*
X382664Y373753D03*
X393750Y398810D03*
X382664Y398753D03*
X393750Y423810D03*
X403692Y-481375D03*
Y-456375D03*
X403780Y-128853D03*
Y-103853D03*
X403750Y-82222D03*
D03*
Y-57222D03*
D03*
Y200538D03*
D03*
Y225538D03*
D03*
Y247050D03*
D03*
Y272050D03*
D03*
Y398810D03*
D03*
Y423810D03*
D03*
X413750Y-82222D03*
Y-57222D03*
Y200538D03*
Y225538D03*
Y247050D03*
Y272050D03*
Y398810D03*
Y423810D03*
G54D103*
X161877Y107140D03*
Y103400D03*
Y99660D03*
X171523D03*
Y107140D03*
G54D121*
X377576Y-165691D03*
X377604Y62581D03*
X408750Y-70872D03*
X398750Y258400D03*
G54D10*
X-56709Y43008D03*
X-61709Y56192D03*
X-51709D03*
X-61100Y250316D03*
X-56100Y263500D03*
X-61000Y382816D03*
X-56000Y396000D03*
X-51100Y250316D03*
X-51000Y382816D03*
X-30000Y43000D03*
X-35000Y56184D03*
X-25000D03*
X-25100Y250316D03*
X-35100D03*
X-30100Y263500D03*
X-36000Y418816D03*
X-26000D03*
X-31000Y432000D03*
G54D112*
X246858Y356835D03*
Y390063D03*
X311819Y356835D03*
Y390063D03*
G54D113*
X238551Y373449D03*
Y369512D03*
Y365575D03*
Y381323D03*
Y377386D03*
X255165Y375417D03*
Y371481D03*
Y367543D03*
Y363606D03*
Y383292D03*
Y379355D03*
X303512Y373449D03*
Y369512D03*
Y365575D03*
Y381323D03*
Y377386D03*
X320126Y375417D03*
Y371481D03*
Y367543D03*
Y363606D03*
Y383292D03*
Y379355D03*
G54D122*
X377664Y18131D03*
Y387403D03*
X408750Y214188D03*
X398750Y412460D03*
G54D20*
X18242Y259777D03*
X29947Y184247D03*
X44017Y38000D03*
X42103Y58317D03*
X44236Y187525D03*
X42403Y191535D03*
X37266Y184311D03*
X42501Y210701D03*
X48817Y264600D03*
X41421Y259638D03*
X36917Y317100D03*
X47017Y332000D03*
X35017Y338000D03*
X47017Y336000D03*
Y340000D03*
X38017Y348500D03*
Y352000D03*
X47017Y387700D03*
X47417Y397850D03*
Y401350D03*
X41517Y415700D03*
Y419700D03*
X34617Y411900D03*
Y415700D03*
X50733Y34873D03*
X51917Y220600D03*
X76517Y259200D03*
X90017Y255500D03*
X89767Y417000D03*
Y412500D03*
X104517Y80000D03*
X109818Y62963D03*
Y66963D03*
X123517Y114000D03*
Y131000D03*
X118817Y350300D03*
X126517Y54300D03*
X147593Y187354D03*
X152957Y242750D03*
X150617Y432600D03*
X155917Y158300D03*
X155617Y163400D03*
X156217Y167100D03*
X155717Y171000D03*
X154317Y195700D03*
X156874Y212568D03*
X155317Y301000D03*
Y297000D03*
Y305100D03*
X183017Y96000D03*
X177917Y272800D03*
X176017Y325200D03*
Y329200D03*
X174517Y432600D03*
X192317Y111300D03*
X194087Y260830D03*
X196617Y268700D03*
X183417Y300200D03*
Y304200D03*
X202517Y273000D03*
X214437Y97984D03*
X223017Y304600D03*
X223657Y372400D03*
X223647Y383260D03*
X229717Y258200D03*
X240521Y313514D03*
Y319310D03*
X246965Y257365D03*
X250330Y268403D03*
X247517Y313500D03*
Y322000D03*
X259017Y110300D03*
X258417Y259900D03*
X266978Y364610D03*
Y385343D03*
X270017Y399500D03*
X277267Y123250D03*
X300517Y57000D03*
X297517Y307000D03*
X288517Y372700D03*
X290242Y367508D03*
X289778Y391600D03*
X316117Y62700D03*
X308317Y134300D03*
X305398Y285092D03*
Y281088D03*
Y277100D03*
X305017Y311500D03*
X326144Y148439D03*
X330017Y358500D03*
Y376500D03*
Y367500D03*
Y372000D03*
Y363000D03*
Y381000D03*
Y385500D03*
X334317Y66000D03*
Y74000D03*
X334577Y125500D03*
X333817Y295900D03*
G54D104*
X176953Y266800D03*
X171047D03*
X297821Y108055D03*
X291380Y106255D03*
X297821Y122106D03*
X291380Y120306D03*
X297821Y113961D03*
X291380Y112161D03*
X297821Y128012D03*
X291380Y126212D03*
X310661Y108055D03*
X304259Y106255D03*
Y120306D03*
X310661Y122106D03*
Y113961D03*
X304259Y112161D03*
Y126212D03*
X310661Y128012D03*
G54D11*
X-23737Y543288D03*
X-16737Y536288D03*
X-16500Y544500D03*
X6590Y264520D03*
X10000Y123500D03*
X7800Y194400D03*
X10800Y234200D03*
X15500Y252000D03*
X10500Y245400D03*
X25600Y106300D03*
X36292Y208592D03*
X50700Y439100D03*
X62321Y69200D03*
X62259Y211100D03*
X54975Y215900D03*
X62520Y233600D03*
X55240Y243700D03*
X58800Y265000D03*
X63945Y427055D03*
X71589Y118250D03*
X67400Y155600D03*
X76000Y175100D03*
X81000Y212330D03*
X70289Y227521D03*
X80200Y234100D03*
X67699Y235380D03*
X69187Y429000D03*
X94500Y127000D03*
X83950Y134950D03*
X86000Y147700D03*
X92200Y141540D03*
X85794Y227069D03*
X84941Y232100D03*
X89675Y421940D03*
X88565Y433040D03*
X105030Y96300D03*
X109800Y422300D03*
X103070Y432630D03*
X110200Y431600D03*
X124000Y50100D03*
X124801Y148130D03*
X123906Y188194D03*
X121200Y234890D03*
X119600Y261500D03*
X137540Y169500D03*
X129810Y191310D03*
X132398Y232400D03*
X132100Y346600D03*
X148314Y193687D03*
X155500Y200500D03*
X153000Y348600D03*
X164982Y164842D03*
X164472Y169902D03*
X164601Y181492D03*
X164426Y174982D03*
X165000Y191807D03*
X164879Y186543D03*
X164800Y198000D03*
X163500Y229184D03*
X167500Y312500D03*
X160500Y318500D03*
X166000Y305500D03*
X169600Y432670D03*
X166450Y424810D03*
X161120Y424590D03*
X181595Y142905D03*
X183500Y245500D03*
X181750Y337300D03*
X178300Y348600D03*
X179800Y423989D03*
X190912Y90313D03*
X191100Y96066D03*
X198703Y143302D03*
X186800Y142800D03*
X192194Y142712D03*
X190708Y245541D03*
X196170Y245552D03*
X188500Y274900D03*
X192500Y278000D03*
X192380Y291900D03*
X191199Y300200D03*
X191230Y305500D03*
X188546Y326356D03*
X200274Y410960D03*
X200048Y418652D03*
X195000Y422540D03*
X186720Y432490D03*
X212872Y48793D03*
X211400Y59238D03*
X200900Y110800D03*
X206200Y102200D03*
X214814Y142700D03*
X203703Y143307D03*
X202600Y245500D03*
X213000Y250500D03*
X206440Y261171D03*
X214034Y261482D03*
X205900Y266130D03*
X204207Y278200D03*
X213700Y363100D03*
X208300Y398150D03*
X202674Y404600D03*
X208830Y424500D03*
X229900Y61000D03*
X227547Y74275D03*
X215900Y73800D03*
X227760Y82524D03*
X217262Y129294D03*
X224784Y142600D03*
X219800Y143250D03*
X230400Y249600D03*
X220866Y272160D03*
X226405Y266335D03*
X229220Y283250D03*
X217400Y295200D03*
X217673Y300600D03*
X228300Y319400D03*
X218100Y305600D03*
X226075Y309390D03*
X228230Y340040D03*
X219800Y364200D03*
X224101Y352320D03*
X226428Y411600D03*
X233400Y123100D03*
X241900Y114300D03*
X233511Y129594D03*
Y142983D03*
X241100Y245510D03*
X244150Y250920D03*
X235326Y245472D03*
X235006Y263591D03*
X234500Y293500D03*
X237900Y324300D03*
X237500Y343000D03*
X235370Y403500D03*
X241231Y407285D03*
X257145Y279700D03*
X257900Y312100D03*
X249400Y410300D03*
X251800Y416600D03*
X257900Y416700D03*
X256400Y431500D03*
X250800Y432500D03*
X264989Y101732D03*
X271500Y111600D03*
X267204Y185566D03*
X274835Y189927D03*
X262100Y280700D03*
X268170Y359840D03*
X273580Y354250D03*
X272581Y376280D03*
X268200Y373400D03*
Y390100D03*
X274880Y387292D03*
X260300Y403370D03*
X270000Y431600D03*
X261400Y433100D03*
X280125Y55200D03*
X280293Y60430D03*
X289736Y78607D03*
X280270Y88470D03*
X284222Y103300D03*
X275528Y163811D03*
X281889Y287636D03*
X285911Y279569D03*
X286372Y320700D03*
X288200Y348300D03*
X276400Y370400D03*
X285500Y426100D03*
X278400Y426400D03*
X284200Y432900D03*
X293773Y73530D03*
X302091Y74553D03*
X291720Y95610D03*
X298575Y101900D03*
X303600Y132200D03*
X302001Y242900D03*
X298100Y283900D03*
X290120Y339370D03*
X290501Y377400D03*
X290450Y382690D03*
X315080Y95980D03*
X310768Y102012D03*
X307101Y249100D03*
X313763Y274756D03*
X312300Y340700D03*
X328000Y62100D03*
X322500Y102900D03*
X320779Y111030D03*
X327383Y164347D03*
X327830Y174403D03*
X324777Y182042D03*
X328265Y187045D03*
X328100Y293800D03*
X341000Y61300D03*
X345195Y105845D03*
X343600Y118900D03*
X337004Y202113D03*
Y210113D03*
G54D21*
X17000Y317016D03*
X20205Y252653D03*
X21000Y317016D03*
X42392Y195803D03*
X46392D03*
X44375Y252626D03*
X44470Y263916D03*
X40500Y357016D03*
X47500Y352016D03*
X40500Y385516D03*
Y392516D03*
X40800Y423516D03*
X52500Y70016D03*
X52055Y123714D03*
X50392Y195803D03*
X60400Y186916D03*
X51849Y203274D03*
X61200Y276916D03*
X61000Y328016D03*
X63000Y403016D03*
X64000Y130216D03*
X75500Y155016D03*
X72800Y180816D03*
X65100Y277016D03*
X74500Y274016D03*
X64900Y328016D03*
X76500Y328146D03*
X68800Y328316D03*
X75000Y403016D03*
X66250Y418266D03*
X91925Y119112D03*
X92405Y131997D03*
X81500Y167416D03*
X83500Y269516D03*
X87500D03*
X79500D03*
X92500Y403016D03*
X88500D03*
X84500D03*
X108500Y39016D03*
X106800Y85016D03*
X101500Y258016D03*
X97300Y257816D03*
X100500Y403016D03*
X104500D03*
X108500D03*
X116500Y39016D03*
X120331Y240016D03*
X122500Y253716D03*
X121918Y328504D03*
X116500Y403116D03*
X119100Y396316D03*
X112500Y403016D03*
X126200Y79516D03*
X132900Y181216D03*
X138000Y208016D03*
X132398Y224708D03*
X128720Y224706D03*
X137918Y328504D03*
X125918D03*
X129300Y426016D03*
X145500Y140516D03*
X148387Y150231D03*
X148400Y164616D03*
X148370Y172266D03*
X142150Y184091D03*
X149500Y229516D03*
X145600Y235416D03*
X142300Y275716D03*
X141918Y328504D03*
X143945Y348664D03*
X147900Y348616D03*
X143000Y419516D03*
X145200Y429466D03*
X163673Y85746D03*
X159673D03*
X159120Y119136D03*
X156500Y132516D03*
X160032Y216735D03*
X153500Y229016D03*
X164801Y257477D03*
X160973Y249527D03*
X153918Y328504D03*
X165026Y343712D03*
X157600Y429516D03*
X161450D03*
X173097Y85746D03*
X169097D03*
X171900Y134916D03*
X177413Y249527D03*
X173992Y257477D03*
X169967D03*
X171276Y423712D03*
X181400Y429716D03*
X175100Y423416D03*
X183800Y120016D03*
X195983Y134885D03*
X188000Y134916D03*
X192000D03*
X183413Y250227D03*
X191538Y250352D03*
X187550Y259756D03*
X193750Y368266D03*
X210778Y108860D03*
X212757Y134885D03*
X208627D03*
X204063Y250302D03*
X211700Y429216D03*
X207300D03*
X215000Y41016D03*
X214785Y108858D03*
X221278Y134885D03*
X217262D03*
X225284D03*
X220600Y324816D03*
X222800Y376291D03*
X213500Y386016D03*
X226500Y403816D03*
X219600Y429216D03*
X215700D03*
X234600Y108016D03*
X229396Y134885D03*
X238500Y332016D03*
X242500Y340516D03*
X243700Y106116D03*
X254332Y114174D03*
X250212Y135803D03*
X246205D03*
X256128Y250195D03*
X250505Y250169D03*
X242940Y258482D03*
X269800Y102416D03*
X258339Y114174D03*
X271674Y145320D03*
X272037Y245468D03*
X269400Y281516D03*
X267000Y416916D03*
X271900Y423816D03*
X257900Y423716D03*
X261900D03*
X277000Y44516D03*
X281300Y108416D03*
X285295Y120397D03*
X281250Y116016D03*
X277200D03*
X275684Y145320D03*
X279582Y245668D03*
X273250Y272516D03*
X284475Y372024D03*
X290000Y62516D03*
X301936Y146388D03*
X292000Y291016D03*
X299000Y291516D03*
X316066Y102834D03*
X316700Y119916D03*
X309936Y146388D03*
X313936D03*
X305936D03*
X311000Y323516D03*
X329825Y275913D03*
X330900Y317416D03*
X337223Y230573D03*
X337600Y275916D03*
G54D114*
X271500Y47559D03*
Y42441D03*
X264500D03*
Y45000D03*
Y47559D03*
X286000Y51941D03*
Y54500D03*
Y57059D03*
X293000D03*
Y51941D03*
G54D105*
X197200Y71000D03*
Y80000D03*
X208800Y71000D03*
Y80000D03*
G54D30*
X22282Y190078D03*
X33306Y203464D03*
G54D123*
X378560Y-162441D03*
X376592D03*
X376680Y14881D03*
X378648D03*
X378588Y65831D03*
X376620D03*
X376680Y384153D03*
X378648D03*
X399734Y261650D03*
X397766D03*
Y409210D03*
X399734D03*
X409734Y-67622D03*
X407766D03*
Y210938D03*
X409734D03*
G54D12*
X14961Y10591D03*
X48031D03*
X261418Y12166D03*
X294488D03*
X306300Y10591D03*
X339370D03*
G54D22*
X16916Y328600D03*
X33816Y214700D03*
X27181Y246113D03*
X27816Y264500D03*
X25216Y316900D03*
X37016Y38000D03*
X42500Y214718D03*
X43616Y241000D03*
X44416Y248800D03*
X36508Y246116D03*
X43616Y244900D03*
X48816Y260800D03*
X34816Y264500D03*
X47016Y328000D03*
Y324000D03*
Y344000D03*
Y348000D03*
Y364000D03*
Y368000D03*
Y372000D03*
Y376000D03*
Y380000D03*
Y384000D03*
X47416Y394350D03*
X50732Y38500D03*
X63491Y116450D03*
X51666Y211200D03*
X78082Y118216D03*
X74535Y135866D03*
X91506Y428020D03*
X108016Y102000D03*
Y107500D03*
X115116Y102000D03*
Y107600D03*
X114516Y123500D03*
X118816Y346400D03*
Y342500D03*
X116016Y415000D03*
X127516Y50000D03*
X134016Y201500D03*
X130516Y253700D03*
X129716Y261900D03*
X136916Y348300D03*
Y351900D03*
X133116Y429000D03*
X149516Y142000D03*
X140516Y175200D03*
X140526Y179160D03*
X148610Y182594D03*
X146596Y419250D03*
X150516Y429000D03*
X163316Y112800D03*
X156421Y153077D03*
X155625Y182644D03*
X155732Y178679D03*
X155716Y174800D03*
X155766Y187354D03*
X155816Y191700D03*
X156516Y224000D03*
X155315Y313560D03*
X155316Y309700D03*
X158016Y350500D03*
X183016Y88000D03*
Y92000D03*
X171416Y272800D03*
X187016Y267000D03*
X194016Y264810D03*
X184616Y294500D03*
X189216Y311100D03*
X207656Y244900D03*
X206816Y419600D03*
X214436Y102014D03*
X222136Y258930D03*
X223016Y296600D03*
Y300600D03*
X217916Y416000D03*
X233316Y319400D03*
X254316Y98600D03*
Y95100D03*
X252116Y110300D03*
X266977Y368610D03*
Y381075D03*
X281226Y93260D03*
X273736Y99350D03*
X283074Y138403D03*
X294516Y79500D03*
X289016Y100400D03*
X294776Y142907D03*
X297516Y311500D03*
X290241Y358508D03*
Y363008D03*
X289777Y387500D03*
X303016Y79500D03*
X305397Y273256D03*
X326143Y144423D03*
X321396Y275940D03*
X320175Y294816D03*
X334316Y70000D03*
X334341Y154911D03*
Y164911D03*
Y159911D03*
Y169911D03*
Y179911D03*
Y174911D03*
Y183926D03*
Y189911D03*
X333840Y292085D03*
G54D31*
X26613Y191653D03*
X28975D03*
Y201889D03*
G54D115*
X295402Y45224D03*
Y41878D03*
G54D40*
X30705Y252508D03*
G54D106*
X197111Y88586D03*
Y92326D03*
Y96066D03*
X205969Y92326D03*
Y88586D03*
Y96066D03*
G54D124*
X441000Y-444000D03*
X451000D03*
Y-355000D03*
X441000D03*
Y-323400D03*
X451000D03*
Y-245000D03*
X441000D03*
X451000Y-215000D03*
X441000D03*
Y-136600D03*
X451000D03*
Y-107000D03*
X441000D03*
Y-18000D03*
X451000D03*
X441000Y12000D03*
X451000D03*
Y96000D03*
X441000D03*
Y126000D03*
X451000D03*
Y200000D03*
X441000D03*
X451000Y230000D03*
X441000D03*
Y304000D03*
X451000D03*
Y336000D03*
X441000D03*
Y420000D03*
X451000D03*
G54D13*
X17716Y18465D03*
X45276D03*
X264173Y20040D03*
X291733D03*
X309055Y18465D03*
X336615D03*
G54D23*
X17000Y319983D03*
X20205Y255620D03*
X21000Y319983D03*
X42392Y198770D03*
X46392D03*
X44375Y255593D03*
X44470Y266883D03*
X40500Y359983D03*
X47500Y354983D03*
X40500Y388483D03*
Y395483D03*
X40800Y426483D03*
X52500Y72983D03*
X52055Y126681D03*
X60400Y189883D03*
X51849Y206241D03*
X50392Y198770D03*
X61200Y279883D03*
X61000Y330983D03*
X63000Y405983D03*
X64000Y133183D03*
X75500Y157983D03*
X72800Y183783D03*
X65100Y279983D03*
X74500Y276983D03*
X64900Y330983D03*
X76500Y331113D03*
X68800Y331283D03*
X75000Y405983D03*
X66250Y421233D03*
X91925Y122079D03*
X92405Y134964D03*
X81500Y170383D03*
X83500Y272483D03*
X87500D03*
X79500D03*
X92500Y405983D03*
X88500D03*
X84500D03*
X108500Y41983D03*
X106800Y87983D03*
X101500Y260983D03*
X97300Y260783D03*
X100500Y405983D03*
X104500D03*
X108500D03*
X116500Y41983D03*
X120331Y242983D03*
X122500Y256683D03*
X121918Y331471D03*
X116500Y406083D03*
X119100Y399283D03*
X112500Y405983D03*
X126200Y82483D03*
X132900Y184183D03*
X138000Y210983D03*
X132398Y227675D03*
X128720Y227673D03*
X137918Y331471D03*
X125918D03*
X129300Y428983D03*
X145500Y143483D03*
X148387Y153198D03*
X148400Y167583D03*
X148370Y175233D03*
X142150Y187058D03*
X149500Y232483D03*
X145600Y238383D03*
X142300Y278683D03*
X141918Y331471D03*
X143945Y351631D03*
X147900Y351583D03*
X145200Y432433D03*
X143000Y422483D03*
X163673Y88713D03*
X159673D03*
X159120Y122103D03*
X156500Y135483D03*
X160032Y219702D03*
X153500Y231983D03*
X160973Y252494D03*
X164801Y260444D03*
X153918Y331471D03*
X165026Y346679D03*
X157600Y432483D03*
X161450D03*
X173097Y88713D03*
X169097D03*
X171900Y137883D03*
X177413Y252494D03*
X173992Y260444D03*
X169967D03*
X171276Y426679D03*
X181400Y432683D03*
X175100Y426383D03*
X183800Y122983D03*
X195983Y137852D03*
X188000Y137883D03*
X192000D03*
X183413Y253194D03*
X191538Y253319D03*
X187550Y262723D03*
X193750Y371233D03*
X210778Y111827D03*
X212757Y137852D03*
X208627D03*
X204063Y253269D03*
X211700Y432183D03*
X207300D03*
X215000Y43983D03*
X214785Y111825D03*
X221278Y137852D03*
X217262D03*
X225284D03*
X220600Y327783D03*
X213500Y388983D03*
X222800Y379258D03*
X226500Y406783D03*
X219600Y432183D03*
X215700D03*
X234600Y110983D03*
X229396Y137852D03*
X238500Y334983D03*
X242500Y343483D03*
X254332Y117141D03*
X243700Y109083D03*
X250212Y138770D03*
X246205D03*
X256128Y253162D03*
X250505Y253136D03*
X242940Y261449D03*
X269800Y105383D03*
X258339Y117141D03*
X271674Y148287D03*
X272037Y248435D03*
X269400Y284483D03*
X267000Y419883D03*
X271900Y426783D03*
X257900Y426683D03*
X261900D03*
X277000Y47483D03*
X285295Y123364D03*
X281250Y118983D03*
X281300Y111383D03*
X277200Y118983D03*
X275684Y148287D03*
X279582Y248635D03*
X273250Y275483D03*
X284475Y374991D03*
X290000Y65483D03*
X301936Y149355D03*
X292000Y293983D03*
X299000Y294483D03*
X316066Y105801D03*
X316700Y122883D03*
X309936Y149355D03*
X313936D03*
X305936D03*
X311000Y326483D03*
X329825Y278880D03*
X330900Y320383D03*
X337223Y233540D03*
X337600Y278883D03*
G54D14*
X22047Y46417D03*
X333466D03*
G54D107*
X197012Y296565D03*
Y304635D03*
X210988Y296565D03*
Y304635D03*
G54D41*
X26768Y251327D03*
G54D125*
X441000Y-454000D03*
X451000D03*
Y-345000D03*
X441000D03*
Y-333400D03*
X451000D03*
Y-235000D03*
X441000D03*
X451000Y-225000D03*
X441000D03*
Y-126600D03*
X451000D03*
Y-117000D03*
X441000D03*
Y-8000D03*
X451000D03*
X441000Y2000D03*
X451000D03*
Y106000D03*
X441000D03*
Y116000D03*
X451000D03*
Y210000D03*
X441000D03*
X451000Y220000D03*
X441000D03*
Y314000D03*
X451000D03*
Y326000D03*
X441000D03*
Y430000D03*
X451000D03*
G54D116*
X293907Y164990D03*
X290757D03*
X287608D03*
X293907Y168140D03*
X290757D03*
X287608D03*
X293907Y171289D03*
X290757D03*
X287608D03*
X293907Y174439D03*
X290757D03*
X287608D03*
X293907Y177588D03*
X290757D03*
X287608D03*
X293907Y180738D03*
X290757D03*
X287608D03*
X293907Y183888D03*
X290757D03*
X287608D03*
X293907Y187037D03*
X290757D03*
X287608D03*
X293907Y190187D03*
X290757D03*
X287608D03*
X293907Y193336D03*
X290757D03*
X287608D03*
X293907Y196486D03*
X290757D03*
X287608D03*
X293907Y199636D03*
X290757D03*
X287608D03*
X293907Y202785D03*
X290757D03*
X287608D03*
X293907Y205935D03*
X290757D03*
X287608D03*
X293907Y209084D03*
X290757D03*
X287608D03*
X293907Y212234D03*
X290757D03*
X287608D03*
X312804Y164990D03*
X309655D03*
X306505D03*
X312804Y168140D03*
X309655D03*
X306505D03*
X312804Y171289D03*
X309655D03*
X306505D03*
X312804Y174439D03*
X309655D03*
X306505D03*
X312804Y177588D03*
X309655D03*
X306505D03*
X312804Y180738D03*
X309655D03*
X306505D03*
X312804Y183888D03*
X309655D03*
X306505D03*
X312804Y187037D03*
X309655D03*
X306505D03*
X312804Y190187D03*
X309655D03*
X306505D03*
X312804Y193336D03*
X309655D03*
X306505D03*
X312804Y196486D03*
X309655D03*
X306505D03*
X312804Y199636D03*
X309655D03*
X306505D03*
X312804Y202785D03*
X309655D03*
X306505D03*
X312804Y205935D03*
X309655D03*
X306505D03*
X312804Y209084D03*
X309655D03*
X306505D03*
X312804Y212234D03*
X309655D03*
X306505D03*
G54D50*
X45276Y89000D03*
Y109000D03*
X56102Y99000D03*
X197587Y338200D03*
X208413Y328200D03*
Y348200D03*
X254087Y69500D03*
X264913Y59500D03*
Y79500D03*
G54D32*
X33109Y190078D03*
G54D126*
G01X2010999Y-388000D02*
Y1475775D01*
X-407000D01*
Y-386798D01*
Y-755294D01*
Y-793716D01*
X-368578D01*
X1942346D01*
X2010999D01*
Y-725063D01*
Y-388000D01*
G01X-53307Y-609436D02*
Y-684436D01*
X446693D01*
Y-609436D01*
X-53307D01*
G01X-41307Y-674436D02*
Y-679436D01*
G01X-42764Y-674436D02*
X-39850D01*
G01X-34940Y-679436D02*
X-37474D01*
Y-674436D01*
X-34940D01*
G01X-35954Y-676853D02*
X-37474D01*
G01X-32374Y-674436D02*
Y-679436D01*
X-29840D01*
G01X-26007Y-679603D02*
X-26134Y-679519D01*
Y-679353D01*
X-26007Y-679269D01*
X-25880Y-679353D01*
Y-679519D01*
X-26007Y-679603D01*
G01Y-677353D02*
X-26134Y-677269D01*
Y-677103D01*
X-26007Y-677019D01*
X-25880Y-677103D01*
Y-677269D01*
X-26007Y-677353D01*
G01X-21224Y-681103D02*
X-21857Y-680269D01*
X-22174Y-679436D01*
Y-676103D01*
X-21857Y-675269D01*
X-21224Y-674436D01*
G01X-15807D02*
X-16314Y-674603D01*
X-16694Y-675019D01*
X-16947Y-675519D01*
X-17137Y-676186D01*
X-17200Y-676936D01*
X-17137Y-677686D01*
X-16947Y-678353D01*
X-16694Y-678853D01*
X-16314Y-679269D01*
X-15807Y-679436D01*
X-15300Y-679269D01*
X-14920Y-678853D01*
X-14667Y-678353D01*
X-14477Y-677686D01*
X-14414Y-676936D01*
X-14477Y-676186D01*
X-14667Y-675519D01*
X-14920Y-675019D01*
X-15300Y-674603D01*
X-15807Y-674436D01*
G01X-12100Y-678436D02*
X-11720Y-679019D01*
X-11214Y-679353D01*
X-10644Y-679436D01*
X-10137Y-679353D01*
X-9630Y-678936D01*
X-9314Y-678436D01*
X-9250Y-677936D01*
X-9377Y-677353D01*
X-9820Y-676936D01*
X-10264Y-676769D01*
X-10834D01*
G01X-10264D02*
X-9884Y-676519D01*
X-9567Y-676103D01*
X-9440Y-675603D01*
X-9567Y-675103D01*
X-9884Y-674686D01*
X-10454Y-674436D01*
X-11024Y-674519D01*
X-11594Y-674853D01*
G01X-5290Y-681103D02*
X-4657Y-680269D01*
X-4340Y-679436D01*
Y-676103D01*
X-4657Y-675269D01*
X-5290Y-674436D01*
G01X-1900Y-678436D02*
X-1520Y-679019D01*
X-1014Y-679353D01*
X-444Y-679436D01*
X63Y-679353D01*
X570Y-678936D01*
X886Y-678436D01*
X950Y-677936D01*
X823Y-677353D01*
X380Y-676936D01*
X-64Y-676769D01*
X-634D01*
G01X-64D02*
X316Y-676519D01*
X633Y-676103D01*
X760Y-675603D01*
X633Y-675103D01*
X316Y-674686D01*
X-254Y-674436D01*
X-824Y-674519D01*
X-1394Y-674853D01*
G01X3390Y-675269D02*
X3770Y-674769D01*
X4213Y-674519D01*
X4720Y-674436D01*
X5353Y-674603D01*
X5796Y-675019D01*
X5923Y-675519D01*
X5860Y-676019D01*
X5606Y-676436D01*
X4340Y-677269D01*
X3770Y-677853D01*
X3390Y-678686D01*
X3263Y-679436D01*
X5923D01*
G01X9566D02*
X9693Y-678353D01*
X9883Y-677436D01*
X10136Y-676603D01*
X10453Y-675686D01*
X10960Y-674436D01*
X8426D01*
G01X13970Y-677769D02*
X15616D01*
G01X18690Y-675269D02*
X19070Y-674769D01*
X19513Y-674519D01*
X20020Y-674436D01*
X20653Y-674603D01*
X21096Y-675019D01*
X21223Y-675519D01*
X21160Y-676019D01*
X20906Y-676436D01*
X19640Y-677269D01*
X19070Y-677853D01*
X18690Y-678686D01*
X18563Y-679436D01*
X21223D01*
G01X23600Y-678436D02*
X23980Y-679019D01*
X24486Y-679353D01*
X25056Y-679436D01*
X25563Y-679353D01*
X26070Y-678936D01*
X26386Y-678436D01*
X26450Y-677936D01*
X26323Y-677353D01*
X25880Y-676936D01*
X25436Y-676769D01*
X24866D01*
G01X25436D02*
X25816Y-676519D01*
X26133Y-676103D01*
X26260Y-675603D01*
X26133Y-675103D01*
X25816Y-674686D01*
X25246Y-674436D01*
X24676Y-674519D01*
X24106Y-674853D01*
G01X30853Y-679436D02*
Y-674436D01*
X28510Y-678019D01*
X31676D01*
G01X33800Y-678686D02*
X34180Y-679103D01*
X34623Y-679353D01*
X35193Y-679436D01*
X35763Y-679269D01*
X36206Y-678936D01*
X36523Y-678353D01*
X36586Y-677686D01*
X36460Y-677019D01*
X36143Y-676603D01*
X35700Y-676269D01*
X35256Y-676186D01*
X34813Y-676269D01*
X34243Y-676603D01*
X34433Y-674436D01*
X36143D01*
G01X44190Y-679436D02*
Y-674436D01*
X46596D01*
G01X45710Y-676853D02*
X44190D01*
G01X48910Y-679436D02*
X50493Y-674436D01*
X52076Y-679436D01*
G01X51506Y-677686D02*
X49480D01*
G01X54263Y-679436D02*
X56923Y-674436D01*
G01X54263D02*
X56923Y-679436D01*
G01X60693Y-679603D02*
X60566Y-679519D01*
Y-679353D01*
X60693Y-679269D01*
X60820Y-679353D01*
Y-679519D01*
X60693Y-679603D01*
G01Y-677353D02*
X60566Y-677269D01*
Y-677103D01*
X60693Y-677019D01*
X60820Y-677103D01*
Y-677269D01*
X60693Y-677353D01*
G01X65476Y-681103D02*
X64843Y-680269D01*
X64526Y-679436D01*
Y-676103D01*
X64843Y-675269D01*
X65476Y-674436D01*
G01X70893D02*
X70386Y-674603D01*
X70006Y-675019D01*
X69753Y-675519D01*
X69563Y-676186D01*
X69500Y-676936D01*
X69563Y-677686D01*
X69753Y-678353D01*
X70006Y-678853D01*
X70386Y-679269D01*
X70893Y-679436D01*
X71400Y-679269D01*
X71780Y-678853D01*
X72033Y-678353D01*
X72223Y-677686D01*
X72286Y-676936D01*
X72223Y-676186D01*
X72033Y-675519D01*
X71780Y-675019D01*
X71400Y-674603D01*
X70893Y-674436D01*
G01X74600Y-678436D02*
X74980Y-679019D01*
X75486Y-679353D01*
X76056Y-679436D01*
X76563Y-679353D01*
X77070Y-678936D01*
X77386Y-678436D01*
X77450Y-677936D01*
X77323Y-677353D01*
X76880Y-676936D01*
X76436Y-676769D01*
X75866D01*
G01X76436D02*
X76816Y-676519D01*
X77133Y-676103D01*
X77260Y-675603D01*
X77133Y-675103D01*
X76816Y-674686D01*
X76246Y-674436D01*
X75676Y-674519D01*
X75106Y-674853D01*
G01X81410Y-681103D02*
X82043Y-680269D01*
X82360Y-679436D01*
Y-676103D01*
X82043Y-675269D01*
X81410Y-674436D01*
G01X84800Y-678436D02*
X85180Y-679019D01*
X85686Y-679353D01*
X86256Y-679436D01*
X86763Y-679353D01*
X87270Y-678936D01*
X87586Y-678436D01*
X87650Y-677936D01*
X87523Y-677353D01*
X87080Y-676936D01*
X86636Y-676769D01*
X86066D01*
G01X86636D02*
X87016Y-676519D01*
X87333Y-676103D01*
X87460Y-675603D01*
X87333Y-675103D01*
X87016Y-674686D01*
X86446Y-674436D01*
X85876Y-674519D01*
X85306Y-674853D01*
G01X90216Y-678853D02*
X90660Y-679269D01*
X91166Y-679436D01*
X91673Y-679269D01*
X92116Y-678769D01*
X92433Y-678019D01*
X92560Y-677269D01*
Y-676353D01*
X92433Y-675603D01*
X92116Y-674936D01*
X91736Y-674603D01*
X91293Y-674436D01*
X90786Y-674603D01*
X90406Y-674936D01*
X90153Y-675436D01*
X90026Y-676103D01*
X90153Y-676686D01*
X90470Y-677269D01*
X90850Y-677603D01*
X91293Y-677686D01*
X91800Y-677519D01*
X92180Y-677103D01*
X92560Y-676353D01*
G01X96266Y-679436D02*
X96393Y-678353D01*
X96583Y-677436D01*
X96836Y-676603D01*
X97153Y-675686D01*
X97660Y-674436D01*
X95126D01*
G01X100670Y-677769D02*
X102316D01*
G01X105200Y-678436D02*
X105580Y-679019D01*
X106086Y-679353D01*
X106656Y-679436D01*
X107163Y-679353D01*
X107670Y-678936D01*
X107986Y-678436D01*
X108050Y-677936D01*
X107923Y-677353D01*
X107480Y-676936D01*
X107036Y-676769D01*
X106466D01*
G01X107036D02*
X107416Y-676519D01*
X107733Y-676103D01*
X107860Y-675603D01*
X107733Y-675103D01*
X107416Y-674686D01*
X106846Y-674436D01*
X106276Y-674519D01*
X105706Y-674853D01*
G01X110490Y-677353D02*
X110933Y-676769D01*
X111313Y-676436D01*
X111820Y-676269D01*
X112263Y-676436D01*
X112580Y-676769D01*
X112833Y-677269D01*
X112896Y-677853D01*
X112833Y-678353D01*
X112580Y-678853D01*
X112200Y-679269D01*
X111756Y-679436D01*
X111250Y-679269D01*
X110806Y-678769D01*
X110553Y-678019D01*
X110490Y-677186D01*
X110616Y-676103D01*
X110806Y-675519D01*
X111123Y-674936D01*
X111566Y-674519D01*
X112010Y-674436D01*
X112453Y-674603D01*
X112770Y-675019D01*
G01X116793Y-679436D02*
Y-674436D01*
X116033Y-675436D01*
G01Y-679436D02*
X117553D01*
G01X122653D02*
Y-674436D01*
X120310Y-678019D01*
X123476D01*
G01X141693Y-609436D02*
Y-684436D01*
G01Y-659436D02*
X244693D01*
Y-634436D01*
G01X141693D02*
X244693D01*
G01X246693Y-609436D02*
Y-684436D01*
G01X244693Y-609436D02*
Y-684436D01*
G01X252200Y-669436D02*
Y-664436D01*
X253466D01*
X253973Y-664686D01*
X254353Y-665019D01*
X254670Y-665519D01*
X254923Y-666103D01*
X254986Y-666936D01*
X254923Y-667769D01*
X254670Y-668353D01*
X254353Y-668853D01*
X253973Y-669186D01*
X253466Y-669436D01*
X252200D01*
G01X257110D02*
X258693Y-664436D01*
X260276Y-669436D01*
G01X259706Y-667686D02*
X257680D01*
G01X263793Y-664436D02*
Y-669436D01*
G01X262336Y-664436D02*
X265250D01*
G01X270160Y-669436D02*
X267626D01*
Y-664436D01*
X270160D01*
G01X269146Y-666853D02*
X267626D01*
G01X273993Y-669603D02*
X273866Y-669519D01*
Y-669353D01*
X273993Y-669269D01*
X274120Y-669353D01*
Y-669519D01*
X273993Y-669603D01*
G01Y-667353D02*
X273866Y-667269D01*
Y-667103D01*
X273993Y-667019D01*
X274120Y-667103D01*
Y-667269D01*
X273993Y-667353D01*
G01X246693Y-659436D02*
X446693D01*
G01X252326Y-644436D02*
Y-639436D01*
X253846D01*
X254353Y-639686D01*
X254733Y-640269D01*
X254860Y-640936D01*
X254733Y-641603D01*
X254416Y-642103D01*
X253846Y-642353D01*
X252326D01*
G01X257553Y-644603D02*
X259833Y-639436D01*
G01X262336Y-644436D02*
Y-639436D01*
X265250Y-644436D01*
Y-639436D01*
G01X268893Y-644603D02*
X268766Y-644519D01*
Y-644353D01*
X268893Y-644269D01*
X269020Y-644353D01*
Y-644519D01*
X268893Y-644603D01*
G01Y-642353D02*
X268766Y-642269D01*
Y-642103D01*
X268893Y-642019D01*
X269020Y-642103D01*
Y-642269D01*
X268893Y-642353D01*
G01X246693Y-634436D02*
X446693D01*
G01X252326Y-619436D02*
Y-614436D01*
X253846D01*
X254353Y-614686D01*
X254733Y-615269D01*
X254860Y-615936D01*
X254733Y-616603D01*
X254416Y-617103D01*
X253846Y-617353D01*
X252326D01*
G01X257426Y-619436D02*
Y-614436D01*
X259010D01*
X259516Y-614686D01*
X259833Y-615019D01*
X259960Y-615686D01*
X259833Y-616353D01*
X259453Y-616769D01*
X259010Y-617019D01*
X257426D01*
G01X259010D02*
X259960Y-619436D01*
G01X263793D02*
X263286Y-619353D01*
X262843Y-619019D01*
X262463Y-618519D01*
X262210Y-617936D01*
X262083Y-617269D01*
Y-616603D01*
X262210Y-615936D01*
X262463Y-615353D01*
X262843Y-614853D01*
X263286Y-614519D01*
X263793Y-614436D01*
X264300Y-614519D01*
X264743Y-614853D01*
X265123Y-615353D01*
X265376Y-615936D01*
X265503Y-616603D01*
Y-617269D01*
X265376Y-617936D01*
X265123Y-618519D01*
X264743Y-619019D01*
X264300Y-619353D01*
X263793Y-619436D01*
G01X267626Y-618436D02*
X267943Y-618936D01*
X268323Y-619269D01*
X268766Y-619436D01*
X269273Y-619269D01*
X269653Y-618936D01*
X270033Y-618436D01*
X270160Y-617769D01*
Y-614436D01*
G01X275260Y-619436D02*
X272726D01*
Y-614436D01*
X275260D01*
G01X274246Y-616853D02*
X272726D01*
G01X280486Y-614853D02*
X280106Y-614603D01*
X279663Y-614436D01*
X279156D01*
X278586Y-614686D01*
X278143Y-615103D01*
X277826Y-615603D01*
X277573Y-616436D01*
X277510Y-617186D01*
X277636Y-617936D01*
X277826Y-618436D01*
X278206Y-618936D01*
X278650Y-619269D01*
X279093Y-619436D01*
X279536D01*
X279980Y-619269D01*
X280360Y-619019D01*
X280676Y-618686D01*
G01X284193Y-614436D02*
Y-619436D01*
G01X282736Y-614436D02*
X285650D01*
G01X289293Y-619603D02*
X289166Y-619519D01*
Y-619353D01*
X289293Y-619269D01*
X289420Y-619353D01*
Y-619519D01*
X289293Y-619603D01*
G01Y-617353D02*
X289166Y-617269D01*
Y-617103D01*
X289293Y-617019D01*
X289420Y-617103D01*
Y-617269D01*
X289293Y-617353D01*
G01X361693Y-659436D02*
Y-684436D01*
G01X364326Y-661936D02*
Y-666936D01*
X366860D01*
G01X369933Y-661936D02*
X371453D01*
G01X370693D02*
Y-666936D01*
G01X369933D02*
X371453D01*
G01X376300Y-664269D02*
X376553Y-664019D01*
X376743Y-663603D01*
X376870Y-663019D01*
X376743Y-662519D01*
X376490Y-662186D01*
X376046Y-661936D01*
X374336D01*
Y-666936D01*
X376426D01*
X376870Y-666603D01*
X377123Y-666103D01*
X377250Y-665519D01*
X377123Y-664936D01*
X376743Y-664436D01*
X376300Y-664269D01*
X374336D01*
G01X380893Y-667103D02*
X380766Y-667019D01*
Y-666853D01*
X380893Y-666769D01*
X381020Y-666853D01*
Y-667019D01*
X380893Y-667103D01*
G01Y-664853D02*
X380766Y-664769D01*
Y-664603D01*
X380893Y-664519D01*
X381020Y-664603D01*
Y-664769D01*
X380893Y-664853D01*
G01X404693Y-659436D02*
Y-684436D01*
G01Y-634436D02*
Y-659436D01*
G01X412706Y-687603D02*
X412813Y-687478D01*
X412893Y-687269D01*
X412946Y-686978D01*
X412893Y-686728D01*
X412786Y-686561D01*
X412600Y-686436D01*
X411880D01*
Y-688936D01*
X412760D01*
X412946Y-688769D01*
X413053Y-688519D01*
X413106Y-688228D01*
X413053Y-687936D01*
X412893Y-687686D01*
X412706Y-687603D01*
X411880D01*
G01X415173Y-688936D02*
Y-687269D01*
G01Y-687561D02*
X415066Y-687394D01*
X414906Y-687311D01*
X414720Y-687269D01*
X414533Y-687353D01*
X414373Y-687519D01*
X414266Y-687769D01*
X414213Y-688103D01*
X414266Y-688436D01*
X414373Y-688686D01*
X414533Y-688853D01*
X414720Y-688936D01*
X414906Y-688894D01*
X415066Y-688769D01*
X415173Y-688603D01*
G01X416493Y-688644D02*
X416626Y-688811D01*
X416813Y-688936D01*
X416973D01*
X417133Y-688853D01*
X417240Y-688728D01*
X417293Y-688561D01*
X417266Y-688311D01*
X417160Y-688186D01*
X416680Y-687936D01*
X416573Y-687644D01*
X416626Y-687436D01*
X416733Y-687311D01*
X416893Y-687269D01*
X417053Y-687311D01*
X417213Y-687436D01*
G01X418693Y-687811D02*
X419546D01*
X419466Y-687519D01*
X419333Y-687353D01*
X419146Y-687269D01*
X418960Y-687311D01*
X418800Y-687436D01*
X418693Y-687728D01*
X418640Y-687978D01*
Y-688228D01*
X418693Y-688478D01*
X418826Y-688728D01*
X418986Y-688894D01*
X419173Y-688936D01*
X419360Y-688853D01*
X419546Y-688603D01*
G01X420813Y-688936D02*
Y-686436D01*
G01Y-687686D02*
X420946Y-687436D01*
X421106Y-687311D01*
X421266Y-687269D01*
X421506Y-687353D01*
X421666Y-687519D01*
X421773Y-687811D01*
Y-688144D01*
X421720Y-688478D01*
X421613Y-688728D01*
X421426Y-688894D01*
X421266Y-688936D01*
X421106Y-688894D01*
X420946Y-688769D01*
X420813Y-688561D01*
G01X423493Y-688936D02*
X423333Y-688894D01*
X423173Y-688728D01*
X423066Y-688436D01*
X423013Y-688103D01*
X423066Y-687769D01*
X423173Y-687478D01*
X423333Y-687311D01*
X423493Y-687269D01*
X423653Y-687311D01*
X423813Y-687478D01*
X423920Y-687769D01*
X423946Y-688103D01*
X423920Y-688436D01*
X423813Y-688728D01*
X423653Y-688894D01*
X423493Y-688936D01*
G01X426173D02*
Y-687269D01*
G01Y-687561D02*
X426066Y-687394D01*
X425906Y-687311D01*
X425720Y-687269D01*
X425533Y-687353D01*
X425373Y-687519D01*
X425266Y-687769D01*
X425213Y-688103D01*
X425266Y-688436D01*
X425373Y-688686D01*
X425533Y-688853D01*
X425720Y-688936D01*
X425906Y-688894D01*
X426066Y-688769D01*
X426173Y-688603D01*
G01X427520Y-688936D02*
Y-687269D01*
G01Y-687603D02*
X427653Y-687436D01*
X427786Y-687311D01*
X427973Y-687269D01*
X428106Y-687311D01*
X428266Y-687436D01*
G01X430573Y-686436D02*
Y-688936D01*
G01Y-688561D02*
X430466Y-688769D01*
X430306Y-688894D01*
X430120Y-688936D01*
X429906Y-688853D01*
X429746Y-688644D01*
X429640Y-688394D01*
X429613Y-688103D01*
X429640Y-687811D01*
X429746Y-687561D01*
X429906Y-687353D01*
X430120Y-687269D01*
X430306Y-687311D01*
X430440Y-687394D01*
X430573Y-687561D01*
G01X433960Y-688936D02*
Y-686436D01*
X434626D01*
X434840Y-686561D01*
X434973Y-686728D01*
X435026Y-687061D01*
X434973Y-687394D01*
X434813Y-687603D01*
X434626Y-687728D01*
X433960D01*
G01X434626D02*
X435026Y-688936D01*
G01X436293Y-687811D02*
X437146D01*
X437066Y-687519D01*
X436933Y-687353D01*
X436746Y-687269D01*
X436560Y-687311D01*
X436400Y-687436D01*
X436293Y-687728D01*
X436240Y-687978D01*
Y-688228D01*
X436293Y-688478D01*
X436426Y-688728D01*
X436586Y-688894D01*
X436773Y-688936D01*
X436960Y-688853D01*
X437146Y-688603D01*
G01X438413Y-687269D02*
X438893Y-688936D01*
X439373Y-687269D01*
G01X441093Y-689019D02*
X441040Y-688978D01*
Y-688894D01*
X441093Y-688853D01*
X441146Y-688894D01*
Y-688978D01*
X441093Y-689019D01*
G01X443613Y-688936D02*
Y-686436D01*
X442626Y-688228D01*
X443960D01*
G01X444826Y-688936D02*
X445493Y-686436D01*
X446160Y-688936D01*
G01X445920Y-688061D02*
X445066D01*
G01X408593Y-661936D02*
Y-666936D01*
G01X407136Y-661936D02*
X410050D01*
G01X413693Y-666936D02*
X413313Y-666853D01*
X412933Y-666519D01*
X412680Y-665936D01*
X412553Y-665269D01*
X412680Y-664603D01*
X412933Y-664019D01*
X413313Y-663686D01*
X413693Y-663603D01*
X414073Y-663686D01*
X414453Y-664019D01*
X414706Y-664603D01*
X414770Y-665269D01*
X414706Y-665936D01*
X414453Y-666519D01*
X414073Y-666853D01*
X413693Y-666936D01*
G01X418793D02*
X418413Y-666853D01*
X418033Y-666519D01*
X417780Y-665936D01*
X417653Y-665269D01*
X417780Y-664603D01*
X418033Y-664019D01*
X418413Y-663686D01*
X418793Y-663603D01*
X419173Y-663686D01*
X419553Y-664019D01*
X419806Y-664603D01*
X419870Y-665269D01*
X419806Y-665936D01*
X419553Y-666519D01*
X419173Y-666853D01*
X418793Y-666936D01*
G01X423893D02*
Y-661936D01*
G01X428993Y-667103D02*
X428866Y-667019D01*
Y-666853D01*
X428993Y-666769D01*
X429120Y-666853D01*
Y-667019D01*
X428993Y-667103D01*
G01Y-664853D02*
X428866Y-664769D01*
Y-664603D01*
X428993Y-664519D01*
X429120Y-664603D01*
Y-664769D01*
X428993Y-664853D01*
G01X407326Y-641936D02*
Y-636936D01*
X408910D01*
X409416Y-637186D01*
X409733Y-637519D01*
X409860Y-638186D01*
X409733Y-638853D01*
X409353Y-639269D01*
X408910Y-639519D01*
X407326D01*
G01X408910D02*
X409860Y-641936D01*
G01X414960D02*
X412426D01*
Y-636936D01*
X414960D01*
G01X413946Y-639353D02*
X412426D01*
G01X417210Y-636936D02*
X418793Y-641936D01*
X420376Y-636936D01*
G01X423893Y-642103D02*
X423766Y-642019D01*
Y-641853D01*
X423893Y-641769D01*
X424020Y-641853D01*
Y-642019D01*
X423893Y-642103D01*
G01Y-639853D02*
X423766Y-639769D01*
Y-639603D01*
X423893Y-639519D01*
X424020Y-639603D01*
Y-639769D01*
X423893Y-639853D01*
G01X2010999Y-388000D02*
Y1475775D01*
X-407000D01*
Y-386798D01*
Y-755294D01*
Y-793716D01*
X-368578D01*
X1942346D01*
X2010999D01*
Y-725063D01*
Y-388000D01*
G01X-42602Y-671096D02*
X-41975Y-671621D01*
X-41270Y-671936D01*
X-40644D01*
X-40017Y-671621D01*
X-39547Y-671096D01*
X-39312Y-670361D01*
X-39469Y-669626D01*
X-39860Y-668996D01*
X-40565Y-668576D01*
X-41505Y-668366D01*
X-42054Y-667946D01*
X-42289Y-667211D01*
X-42132Y-666476D01*
X-41740Y-665951D01*
X-41192Y-665636D01*
X-40644D01*
X-40095Y-665846D01*
X-39625Y-666371D01*
G01X-36302Y-671936D02*
Y-665636D01*
G01X-33012D02*
Y-671936D01*
G01Y-668786D02*
X-36302D01*
G01X-29297Y-665636D02*
X-27417D01*
G01X-28357D02*
Y-671936D01*
G01X-29297D02*
X-27417D01*
G01X-20490D02*
X-23624D01*
Y-665636D01*
X-20490D01*
G01X-21744Y-668681D02*
X-23624D01*
G01X-17559Y-671936D02*
Y-665636D01*
X-13955Y-671936D01*
Y-665636D01*
G01X-9614Y-673091D02*
X-9300Y-671726D01*
G01X-3157Y-665636D02*
Y-671936D01*
G01X-4959Y-665636D02*
X-1355D01*
G01X1185Y-671936D02*
X3143Y-665636D01*
X5101Y-671936D01*
G01X4396Y-669731D02*
X1890D01*
G01X8503Y-665636D02*
X10383D01*
G01X9443D02*
Y-671936D01*
G01X8503D02*
X10383D01*
G01X13393Y-665636D02*
X14490Y-671936D01*
X15743Y-665636D01*
X16996Y-671936D01*
X18093Y-665636D01*
G01X20085Y-671936D02*
X22043Y-665636D01*
X24001Y-671936D01*
G01X23296Y-669731D02*
X20790D01*
G01X26541Y-671936D02*
Y-665636D01*
X30145Y-671936D01*
Y-665636D01*
G01X39376Y-671936D02*
Y-665636D01*
X41335D01*
X41961Y-665951D01*
X42353Y-666371D01*
X42510Y-667211D01*
X42353Y-668051D01*
X41883Y-668576D01*
X41335Y-668891D01*
X39376D01*
G01X41335D02*
X42510Y-671936D01*
G01X47243Y-672146D02*
X47086Y-672041D01*
Y-671831D01*
X47243Y-671726D01*
X47400Y-671831D01*
Y-672041D01*
X47243Y-672146D01*
G01X53543Y-671936D02*
X52916Y-671831D01*
X52368Y-671411D01*
X51898Y-670781D01*
X51585Y-670046D01*
X51428Y-669206D01*
Y-668366D01*
X51585Y-667526D01*
X51898Y-666791D01*
X52368Y-666161D01*
X52916Y-665741D01*
X53543Y-665636D01*
X54170Y-665741D01*
X54718Y-666161D01*
X55188Y-666791D01*
X55501Y-667526D01*
X55658Y-668366D01*
Y-669206D01*
X55501Y-670046D01*
X55188Y-670781D01*
X54718Y-671411D01*
X54170Y-671831D01*
X53543Y-671936D01*
G01X59843Y-672146D02*
X59686Y-672041D01*
Y-671831D01*
X59843Y-671726D01*
X60000Y-671831D01*
Y-672041D01*
X59843Y-672146D01*
G01X67866Y-666161D02*
X67396Y-665846D01*
X66848Y-665636D01*
X66221D01*
X65516Y-665951D01*
X64968Y-666476D01*
X64576Y-667106D01*
X64263Y-668156D01*
X64185Y-669101D01*
X64341Y-670046D01*
X64576Y-670676D01*
X65046Y-671306D01*
X65595Y-671726D01*
X66143Y-671936D01*
X66691D01*
X67240Y-671726D01*
X67710Y-671411D01*
X68101Y-670991D01*
G01X72443Y-672146D02*
X72286Y-672041D01*
Y-671831D01*
X72443Y-671726D01*
X72600Y-671831D01*
Y-672041D01*
X72443Y-672146D01*
G01X-42680Y-661936D02*
Y-655636D01*
G01X-39704D02*
X-42680Y-659521D01*
G01X-39234Y-661936D02*
X-41349Y-657736D01*
G01X-36380Y-655636D02*
Y-660151D01*
X-36067Y-661096D01*
X-35440Y-661726D01*
X-34657Y-661936D01*
X-33874Y-661726D01*
X-33247Y-661096D01*
X-32934Y-660151D01*
Y-655636D01*
G01X-26790Y-661936D02*
X-29924D01*
Y-655636D01*
X-26790D01*
G01X-28044Y-658681D02*
X-29924D01*
G01X-22997Y-655636D02*
X-21117D01*
G01X-22057D02*
Y-661936D01*
G01X-22997D02*
X-21117D01*
G01X-11102Y-661096D02*
X-10475Y-661621D01*
X-9770Y-661936D01*
X-9144D01*
X-8517Y-661621D01*
X-8047Y-661096D01*
X-7812Y-660361D01*
X-7969Y-659626D01*
X-8360Y-658996D01*
X-9065Y-658576D01*
X-10005Y-658366D01*
X-10554Y-657946D01*
X-10789Y-657211D01*
X-10632Y-656476D01*
X-10240Y-655951D01*
X-9692Y-655636D01*
X-9144D01*
X-8595Y-655846D01*
X-8125Y-656371D01*
G01X-4802Y-661936D02*
Y-655636D01*
G01X-1512D02*
Y-661936D01*
G01Y-658786D02*
X-4802D01*
G01X1185Y-661936D02*
X3143Y-655636D01*
X5101Y-661936D01*
G01X4396Y-659731D02*
X1890D01*
G01X7641Y-661936D02*
Y-655636D01*
X11245Y-661936D01*
Y-655636D01*
G01X20398Y-661936D02*
Y-655636D01*
G01X23688D02*
Y-661936D01*
G01Y-658786D02*
X20398D01*
G01X26698Y-661096D02*
X27325Y-661621D01*
X28030Y-661936D01*
X28656D01*
X29283Y-661621D01*
X29753Y-661096D01*
X29988Y-660361D01*
X29831Y-659626D01*
X29440Y-658996D01*
X28735Y-658576D01*
X27795Y-658366D01*
X27246Y-657946D01*
X27011Y-657211D01*
X27168Y-656476D01*
X27560Y-655951D01*
X28108Y-655636D01*
X28656D01*
X29205Y-655846D01*
X29675Y-656371D01*
G01X33703Y-655636D02*
X35583D01*
G01X34643D02*
Y-661936D01*
G01X33703D02*
X35583D01*
G01X38985D02*
X40943Y-655636D01*
X42901Y-661936D01*
G01X42196Y-659731D02*
X39690D01*
G01X45441Y-661936D02*
Y-655636D01*
X49045Y-661936D01*
Y-655636D01*
G01X54013Y-658786D02*
X55580D01*
Y-660676D01*
X55110Y-661306D01*
X54561Y-661726D01*
X53778Y-661936D01*
X52995Y-661726D01*
X52446Y-661306D01*
X51976Y-660676D01*
X51663Y-659941D01*
X51506Y-659101D01*
Y-658366D01*
X51663Y-657736D01*
X51976Y-657001D01*
X52446Y-656371D01*
X52916Y-655951D01*
X53543Y-655636D01*
X54091D01*
X54718Y-655846D01*
X55188Y-656266D01*
G01X59686Y-663091D02*
X60000Y-661726D01*
G01X66143Y-655636D02*
Y-661936D01*
G01X64341Y-655636D02*
X67945D01*
G01X70485Y-661936D02*
X72443Y-655636D01*
X74401Y-661936D01*
G01X73696Y-659731D02*
X71190D01*
G01X78743Y-661936D02*
X78116Y-661831D01*
X77568Y-661411D01*
X77098Y-660781D01*
X76785Y-660046D01*
X76628Y-659206D01*
Y-658366D01*
X76785Y-657526D01*
X77098Y-656791D01*
X77568Y-656161D01*
X78116Y-655741D01*
X78743Y-655636D01*
X79370Y-655741D01*
X79918Y-656161D01*
X80388Y-656791D01*
X80701Y-657526D01*
X80858Y-658366D01*
Y-659206D01*
X80701Y-660046D01*
X80388Y-660781D01*
X79918Y-661411D01*
X79370Y-661831D01*
X78743Y-661936D01*
G01X91343D02*
Y-659101D01*
X89776Y-655636D01*
G01X92910D02*
X91343Y-659101D01*
G01X95920Y-655636D02*
Y-660151D01*
X96233Y-661096D01*
X96860Y-661726D01*
X97643Y-661936D01*
X98426Y-661726D01*
X99053Y-661096D01*
X99366Y-660151D01*
Y-655636D01*
G01X101985Y-661936D02*
X103943Y-655636D01*
X105901Y-661936D01*
G01X105196Y-659731D02*
X102690D01*
G01X108441Y-661936D02*
Y-655636D01*
X112045Y-661936D01*
Y-655636D01*
G01X-42759Y-651936D02*
Y-645636D01*
X-39155Y-651936D01*
Y-645636D01*
G01X-34657Y-651936D02*
X-35284Y-651831D01*
X-35832Y-651411D01*
X-36302Y-650781D01*
X-36615Y-650046D01*
X-36772Y-649206D01*
Y-648366D01*
X-36615Y-647526D01*
X-36302Y-646791D01*
X-35832Y-646161D01*
X-35284Y-645741D01*
X-34657Y-645636D01*
X-34030Y-645741D01*
X-33482Y-646161D01*
X-33012Y-646791D01*
X-32699Y-647526D01*
X-32542Y-648366D01*
Y-649206D01*
X-32699Y-650046D01*
X-33012Y-650781D01*
X-33482Y-651411D01*
X-34030Y-651831D01*
X-34657Y-651936D01*
G01X-28357Y-652146D02*
X-28514Y-652041D01*
Y-651831D01*
X-28357Y-651726D01*
X-28200Y-651831D01*
Y-652041D01*
X-28357Y-652146D01*
G01X-22057Y-651936D02*
Y-645636D01*
X-22997Y-646896D01*
G01Y-651936D02*
X-21117D01*
G01X-15757D02*
X-15209Y-651831D01*
X-14582Y-651516D01*
X-14190Y-650991D01*
X-14034Y-650256D01*
X-14190Y-649521D01*
X-14660Y-648891D01*
X-15365Y-648576D01*
X-16149D01*
X-16619Y-648366D01*
X-17010Y-647841D01*
X-17167Y-647106D01*
X-16932Y-646371D01*
X-16384Y-645846D01*
X-15757Y-645636D01*
X-15130Y-645846D01*
X-14582Y-646371D01*
X-14347Y-647106D01*
X-14504Y-647841D01*
X-14895Y-648366D01*
X-15365Y-648576D01*
X-16149D01*
X-16854Y-648891D01*
X-17324Y-649521D01*
X-17480Y-650256D01*
X-17324Y-650991D01*
X-16932Y-651516D01*
X-16305Y-651831D01*
X-15757Y-651936D01*
G01X-9457D02*
X-8909Y-651831D01*
X-8282Y-651516D01*
X-7890Y-650991D01*
X-7734Y-650256D01*
X-7890Y-649521D01*
X-8360Y-648891D01*
X-9065Y-648576D01*
X-9849D01*
X-10319Y-648366D01*
X-10710Y-647841D01*
X-10867Y-647106D01*
X-10632Y-646371D01*
X-10084Y-645846D01*
X-9457Y-645636D01*
X-8830Y-645846D01*
X-8282Y-646371D01*
X-8047Y-647106D01*
X-8204Y-647841D01*
X-8595Y-648366D01*
X-9065Y-648576D01*
X-9849D01*
X-10554Y-648891D01*
X-11024Y-649521D01*
X-11180Y-650256D01*
X-11024Y-650991D01*
X-10632Y-651516D01*
X-10005Y-651831D01*
X-9457Y-651936D01*
G01X-3314Y-653091D02*
X-3000Y-651726D01*
G01X793Y-645636D02*
X1890Y-651936D01*
X3143Y-645636D01*
X4396Y-651936D01*
X5493Y-645636D01*
G01X11010Y-651936D02*
X7876D01*
Y-645636D01*
X11010D01*
G01X9756Y-648681D02*
X7876D01*
G01X13941Y-651936D02*
Y-645636D01*
X17545Y-651936D01*
Y-645636D01*
G01X26698Y-651936D02*
Y-645636D01*
G01X29988D02*
Y-651936D01*
G01Y-648786D02*
X26698D01*
G01X32293Y-645636D02*
X33390Y-651936D01*
X34643Y-645636D01*
X35896Y-651936D01*
X36993Y-645636D01*
G01X38985Y-651936D02*
X40943Y-645636D01*
X42901Y-651936D01*
G01X42196Y-649731D02*
X39690D01*
G01X52055Y-646686D02*
X52525Y-646056D01*
X53073Y-645741D01*
X53700Y-645636D01*
X54483Y-645846D01*
X55031Y-646371D01*
X55188Y-647001D01*
X55110Y-647631D01*
X54796Y-648156D01*
X53230Y-649206D01*
X52525Y-649941D01*
X52055Y-650991D01*
X51898Y-651936D01*
X55188D01*
G01X58041D02*
Y-645636D01*
X61645Y-651936D01*
Y-645636D01*
G01X64420Y-651936D02*
Y-645636D01*
X65986D01*
X66613Y-645951D01*
X67083Y-646371D01*
X67475Y-647001D01*
X67788Y-647736D01*
X67866Y-648786D01*
X67788Y-649836D01*
X67475Y-650571D01*
X67083Y-651201D01*
X66613Y-651621D01*
X65986Y-651936D01*
X64420D01*
G01X77176D02*
Y-645636D01*
X79135D01*
X79761Y-645951D01*
X80153Y-646371D01*
X80310Y-647211D01*
X80153Y-648051D01*
X79683Y-648576D01*
X79135Y-648891D01*
X77176D01*
G01X79135D02*
X80310Y-651936D01*
G01X83320D02*
Y-645636D01*
X84886D01*
X85513Y-645951D01*
X85983Y-646371D01*
X86375Y-647001D01*
X86688Y-647736D01*
X86766Y-648786D01*
X86688Y-649836D01*
X86375Y-650571D01*
X85983Y-651201D01*
X85513Y-651621D01*
X84886Y-651936D01*
X83320D01*
G01X91343Y-652146D02*
X91186Y-652041D01*
Y-651831D01*
X91343Y-651726D01*
X91500Y-651831D01*
Y-652041D01*
X91343Y-652146D01*
G01X-18657Y-639236D02*
X-21177Y-638819D01*
X-23382Y-637153D01*
X-25272Y-634653D01*
X-26532Y-631736D01*
X-27162Y-628403D01*
Y-625069D01*
X-26532Y-621736D01*
X-25272Y-618819D01*
X-23382Y-616320D01*
X-21177Y-614653D01*
X-18657Y-614236D01*
X-16137Y-614653D01*
X-13932Y-616320D01*
X-12042Y-618819D01*
X-10782Y-621736D01*
X-10152Y-625069D01*
Y-628403D01*
X-10782Y-631736D01*
X-12042Y-634653D01*
X-13932Y-637153D01*
X-16137Y-638819D01*
X-18657Y-639236D01*
G01X-16137Y-632569D02*
X-12357Y-639236D01*
G01X1188Y-622570D02*
Y-634236D01*
X2448Y-637153D01*
X4338Y-638819D01*
X6543Y-639236D01*
X8748Y-638819D01*
X10638Y-637153D01*
X11898Y-634236D01*
G01Y-639236D02*
Y-622570D01*
G01X37413Y-639236D02*
Y-622570D01*
G01Y-625486D02*
X36153Y-623820D01*
X34263Y-622986D01*
X32058Y-622570D01*
X29853Y-623403D01*
X27963Y-625069D01*
X26703Y-627570D01*
X26073Y-630903D01*
X26703Y-634236D01*
X27963Y-636737D01*
X29853Y-638403D01*
X32058Y-639236D01*
X34263Y-638819D01*
X36153Y-637570D01*
X37413Y-635903D01*
G01X51588Y-639236D02*
Y-622570D01*
G01Y-626736D02*
X52848Y-624653D01*
X54738Y-622986D01*
X57258Y-622570D01*
X59463Y-622986D01*
X61353Y-624653D01*
X62298Y-627570D01*
Y-639236D01*
G01X82143Y-614236D02*
Y-639236D01*
G01X77733Y-622570D02*
X86553D01*
G01X113013Y-639236D02*
Y-622570D01*
G01Y-625486D02*
X111753Y-623820D01*
X109863Y-622986D01*
X107658Y-622570D01*
X105453Y-623403D01*
X103563Y-625069D01*
X102303Y-627570D01*
X101673Y-630903D01*
X102303Y-634236D01*
X103563Y-636737D01*
X105453Y-638403D01*
X107658Y-639236D01*
X109863Y-638819D01*
X111753Y-637570D01*
X113013Y-635903D01*
G01X152693Y-618936D02*
Y-626936D01*
X156693D01*
G01X164493D02*
Y-621603D01*
G01Y-622536D02*
X164093Y-622003D01*
X163493Y-621736D01*
X162793Y-621603D01*
X162093Y-621869D01*
X161493Y-622403D01*
X161093Y-623203D01*
X160893Y-624269D01*
X161093Y-625336D01*
X161493Y-626136D01*
X162093Y-626669D01*
X162793Y-626936D01*
X163493Y-626803D01*
X164093Y-626403D01*
X164493Y-625870D01*
G01X168593Y-629336D02*
X169193Y-629603D01*
X169993Y-629336D01*
X170493Y-628803D01*
X170893Y-628136D01*
X171493Y-626003D01*
X172793Y-621603D01*
G01X169593D02*
X171493Y-626003D01*
G01X177193Y-623336D02*
X180393D01*
X180093Y-622403D01*
X179593Y-621869D01*
X178893Y-621603D01*
X178193Y-621736D01*
X177593Y-622136D01*
X177193Y-623069D01*
X176993Y-623870D01*
Y-624669D01*
X177193Y-625469D01*
X177693Y-626269D01*
X178293Y-626803D01*
X178993Y-626936D01*
X179693Y-626669D01*
X180393Y-625870D01*
G01X185293Y-626936D02*
Y-621603D01*
G01Y-622669D02*
X185793Y-622136D01*
X186293Y-621736D01*
X186993Y-621603D01*
X187493Y-621736D01*
X188093Y-622136D01*
G01X166093Y-651936D02*
Y-643936D01*
X168693Y-650603D01*
X171293Y-643936D01*
Y-651936D01*
G01X174193D02*
X176693Y-643936D01*
X179193Y-651936D01*
G01X178293Y-649136D02*
X175093D01*
G01X182593Y-650870D02*
X183393Y-651536D01*
X184293Y-651936D01*
X185093D01*
X185893Y-651536D01*
X186493Y-650870D01*
X186793Y-649936D01*
X186593Y-649003D01*
X186093Y-648203D01*
X185193Y-647669D01*
X183993Y-647403D01*
X183293Y-646869D01*
X182993Y-645936D01*
X183193Y-645003D01*
X183693Y-644336D01*
X184393Y-643936D01*
X185093D01*
X185793Y-644203D01*
X186393Y-644869D01*
G01X190493Y-651936D02*
Y-643936D01*
G01X194293D02*
X190493Y-648870D01*
G01X194893Y-651936D02*
X192193Y-646603D01*
G01X199393Y-649269D02*
X201993D01*
G01X208693Y-643936D02*
Y-651936D01*
G01X206393Y-643936D02*
X210993D01*
G01X216693Y-651936D02*
X215893Y-651803D01*
X215193Y-651269D01*
X214593Y-650469D01*
X214193Y-649536D01*
X213993Y-648469D01*
Y-647403D01*
X214193Y-646336D01*
X214593Y-645403D01*
X215193Y-644603D01*
X215893Y-644069D01*
X216693Y-643936D01*
X217493Y-644069D01*
X218193Y-644603D01*
X218793Y-645403D01*
X219193Y-646336D01*
X219393Y-647403D01*
Y-648469D01*
X219193Y-649536D01*
X218793Y-650469D01*
X218193Y-651269D01*
X217493Y-651803D01*
X216693Y-651936D01*
G01X222693D02*
Y-643936D01*
X225093D01*
X225893Y-644336D01*
X226493Y-645269D01*
X226693Y-646336D01*
X226493Y-647403D01*
X225993Y-648203D01*
X225093Y-648603D01*
X222693D01*
G01X173993Y-676936D02*
Y-668936D01*
G01X177793D02*
X173993Y-673870D01*
G01X178393Y-676936D02*
X175693Y-671603D01*
G01X185993Y-676936D02*
Y-671603D01*
G01Y-672536D02*
X185593Y-672003D01*
X184993Y-671736D01*
X184293Y-671603D01*
X183593Y-671869D01*
X182993Y-672403D01*
X182593Y-673203D01*
X182393Y-674269D01*
X182593Y-675336D01*
X182993Y-676136D01*
X183593Y-676669D01*
X184293Y-676936D01*
X184993Y-676803D01*
X185593Y-676403D01*
X185993Y-675870D01*
G01X192193Y-671603D02*
Y-676936D01*
G01Y-669469D02*
X191993Y-669336D01*
Y-669069D01*
X192193Y-668936D01*
X192393Y-669069D01*
Y-669336D01*
X192193Y-669469D01*
G01X279293Y-670269D02*
X279893Y-669469D01*
X280593Y-669069D01*
X281393Y-668936D01*
X282393Y-669203D01*
X283093Y-669869D01*
X283293Y-670669D01*
X283193Y-671470D01*
X282793Y-672136D01*
X280793Y-673469D01*
X279893Y-674403D01*
X279293Y-675736D01*
X279093Y-676936D01*
X283293D01*
G01X289193Y-668936D02*
X288393Y-669203D01*
X287793Y-669869D01*
X287393Y-670669D01*
X287093Y-671736D01*
X286993Y-672936D01*
X287093Y-674136D01*
X287393Y-675203D01*
X287793Y-676003D01*
X288393Y-676669D01*
X289193Y-676936D01*
X289993Y-676669D01*
X290593Y-676003D01*
X290993Y-675203D01*
X291293Y-674136D01*
X291393Y-672936D01*
X291293Y-671736D01*
X290993Y-670669D01*
X290593Y-669869D01*
X289993Y-669203D01*
X289193Y-668936D01*
G01X295293Y-670269D02*
X295893Y-669469D01*
X296593Y-669069D01*
X297393Y-668936D01*
X298393Y-669203D01*
X299093Y-669869D01*
X299293Y-670669D01*
X299193Y-671470D01*
X298793Y-672136D01*
X296793Y-673469D01*
X295893Y-674403D01*
X295293Y-675736D01*
X295093Y-676936D01*
X299293D01*
G01X303293Y-670269D02*
X303893Y-669469D01*
X304593Y-669069D01*
X305393Y-668936D01*
X306393Y-669203D01*
X307093Y-669869D01*
X307293Y-670669D01*
X307193Y-671470D01*
X306793Y-672136D01*
X304793Y-673469D01*
X303893Y-674403D01*
X303293Y-675736D01*
X303093Y-676936D01*
X307293D01*
G01X311393Y-677203D02*
X314993Y-668936D01*
G01X321193Y-676936D02*
Y-668936D01*
X319993Y-670536D01*
G01Y-676936D02*
X322393D01*
G01X327293Y-670269D02*
X327893Y-669469D01*
X328593Y-669069D01*
X329393Y-668936D01*
X330393Y-669203D01*
X331093Y-669869D01*
X331293Y-670669D01*
X331193Y-671470D01*
X330793Y-672136D01*
X328793Y-673469D01*
X327893Y-674403D01*
X327293Y-675736D01*
X327093Y-676936D01*
X331293D01*
G01X335393Y-677203D02*
X338993Y-668936D01*
G01X345193D02*
X344393Y-669203D01*
X343793Y-669869D01*
X343393Y-670669D01*
X343093Y-671736D01*
X342993Y-672936D01*
X343093Y-674136D01*
X343393Y-675203D01*
X343793Y-676003D01*
X344393Y-676669D01*
X345193Y-676936D01*
X345993Y-676669D01*
X346593Y-676003D01*
X346993Y-675203D01*
X347293Y-674136D01*
X347393Y-672936D01*
X347293Y-671736D01*
X346993Y-670669D01*
X346593Y-669869D01*
X345993Y-669203D01*
X345193Y-668936D01*
G01X351493Y-676003D02*
X352193Y-676669D01*
X352993Y-676936D01*
X353793Y-676669D01*
X354493Y-675870D01*
X354993Y-674669D01*
X355193Y-673469D01*
Y-672003D01*
X354993Y-670803D01*
X354493Y-669736D01*
X353893Y-669203D01*
X353193Y-668936D01*
X352393Y-669203D01*
X351793Y-669736D01*
X351393Y-670536D01*
X351193Y-671603D01*
X351393Y-672536D01*
X351893Y-673469D01*
X352493Y-674003D01*
X353193Y-674136D01*
X353993Y-673870D01*
X354593Y-673203D01*
X355193Y-672003D01*
G01X278993Y-651936D02*
Y-643936D01*
X280993D01*
X281793Y-644336D01*
X282393Y-644869D01*
X282893Y-645669D01*
X283293Y-646603D01*
X283393Y-647936D01*
X283293Y-649269D01*
X282893Y-650203D01*
X282393Y-651003D01*
X281793Y-651536D01*
X280993Y-651936D01*
X278993D01*
G01X286693D02*
X289193Y-643936D01*
X291693Y-651936D01*
G01X290793Y-649136D02*
X287593D01*
G01X297193Y-643936D02*
X296393Y-644203D01*
X295793Y-644869D01*
X295393Y-645669D01*
X295093Y-646736D01*
X294993Y-647936D01*
X295093Y-649136D01*
X295393Y-650203D01*
X295793Y-651003D01*
X296393Y-651669D01*
X297193Y-651936D01*
X297993Y-651669D01*
X298593Y-651003D01*
X298993Y-650203D01*
X299293Y-649136D01*
X299393Y-647936D01*
X299293Y-646736D01*
X298993Y-645669D01*
X298593Y-644869D01*
X297993Y-644203D01*
X297193Y-643936D01*
G01X303293Y-651936D02*
Y-643936D01*
X307093D01*
G01X305693Y-647803D02*
X303293D01*
G01X313193Y-643936D02*
X312393Y-644203D01*
X311793Y-644869D01*
X311393Y-645669D01*
X311093Y-646736D01*
X310993Y-647936D01*
X311093Y-649136D01*
X311393Y-650203D01*
X311793Y-651003D01*
X312393Y-651669D01*
X313193Y-651936D01*
X313993Y-651669D01*
X314593Y-651003D01*
X314993Y-650203D01*
X315293Y-649136D01*
X315393Y-647936D01*
X315293Y-646736D01*
X314993Y-645669D01*
X314593Y-644869D01*
X313993Y-644203D01*
X313193Y-643936D01*
G01X321193D02*
Y-651936D01*
G01X318893Y-643936D02*
X323493D01*
G01X326593Y-651936D02*
Y-643936D01*
X329193Y-650603D01*
X331793Y-643936D01*
Y-651936D01*
G01X334993D02*
Y-643936D01*
X336993D01*
X337793Y-644336D01*
X338393Y-644869D01*
X338893Y-645669D01*
X339293Y-646603D01*
X339393Y-647936D01*
X339293Y-649269D01*
X338893Y-650203D01*
X338393Y-651003D01*
X337793Y-651536D01*
X336993Y-651936D01*
X334993D01*
G01X347393Y-644603D02*
X346793Y-644203D01*
X346093Y-643936D01*
X345293D01*
X344393Y-644336D01*
X343693Y-645003D01*
X343193Y-645803D01*
X342793Y-647136D01*
X342693Y-648336D01*
X342893Y-649536D01*
X343193Y-650336D01*
X343793Y-651136D01*
X344493Y-651669D01*
X345193Y-651936D01*
X345893D01*
X346593Y-651669D01*
X347193Y-651269D01*
X347693Y-650736D01*
G01X350993Y-651936D02*
Y-643936D01*
X352993D01*
X353793Y-644336D01*
X354393Y-644869D01*
X354893Y-645669D01*
X355293Y-646603D01*
X355393Y-647936D01*
X355293Y-649269D01*
X354893Y-650203D01*
X354393Y-651003D01*
X353793Y-651536D01*
X352993Y-651936D01*
X350993D01*
G01X361193Y-643936D02*
X360393Y-644203D01*
X359793Y-644869D01*
X359393Y-645669D01*
X359093Y-646736D01*
X358993Y-647936D01*
X359093Y-649136D01*
X359393Y-650203D01*
X359793Y-651003D01*
X360393Y-651669D01*
X361193Y-651936D01*
X361993Y-651669D01*
X362593Y-651003D01*
X362993Y-650203D01*
X363293Y-649136D01*
X363393Y-647936D01*
X363293Y-646736D01*
X362993Y-645669D01*
X362593Y-644869D01*
X361993Y-644203D01*
X361193Y-643936D01*
G01X298418Y-624819D02*
Y-618519D01*
X301394D01*
G01X300298Y-621564D02*
X298418D01*
G01X306206Y-618519D02*
X305579Y-618729D01*
X305109Y-619254D01*
X304796Y-619884D01*
X304561Y-620724D01*
X304483Y-621669D01*
X304561Y-622614D01*
X304796Y-623454D01*
X305109Y-624084D01*
X305579Y-624609D01*
X306206Y-624819D01*
X306833Y-624609D01*
X307303Y-624084D01*
X307616Y-623454D01*
X307851Y-622614D01*
X307929Y-621669D01*
X307851Y-620724D01*
X307616Y-619884D01*
X307303Y-619254D01*
X306833Y-618729D01*
X306206Y-618519D01*
G01X312506D02*
Y-624819D01*
G01X310704Y-618519D02*
X314308D01*
G01X316456Y-626919D02*
X321156D01*
G01X323069Y-624819D02*
Y-618519D01*
X325106Y-623769D01*
X327143Y-618519D01*
Y-624819D01*
G01X332816D02*
Y-620619D01*
G01Y-621354D02*
X332503Y-620934D01*
X332033Y-620724D01*
X331484Y-620619D01*
X330936Y-620829D01*
X330466Y-621249D01*
X330153Y-621879D01*
X329996Y-622719D01*
X330153Y-623559D01*
X330466Y-624189D01*
X330936Y-624609D01*
X331484Y-624819D01*
X332033Y-624714D01*
X332503Y-624399D01*
X332816Y-623979D01*
G01X336374Y-624819D02*
Y-620619D01*
G01Y-621669D02*
X336688Y-621144D01*
X337158Y-620724D01*
X337784Y-620619D01*
X338333Y-620724D01*
X338803Y-621144D01*
X339038Y-621879D01*
Y-624819D01*
G01X345416D02*
Y-620619D01*
G01Y-621354D02*
X345103Y-620934D01*
X344633Y-620724D01*
X344084Y-620619D01*
X343536Y-620829D01*
X343066Y-621249D01*
X342753Y-621879D01*
X342596Y-622719D01*
X342753Y-623559D01*
X343066Y-624189D01*
X343536Y-624609D01*
X344084Y-624819D01*
X344633Y-624714D01*
X345103Y-624399D01*
X345416Y-623979D01*
G01X349209Y-626394D02*
X349758Y-626814D01*
X350384Y-626919D01*
X350933Y-626814D01*
X351403Y-626289D01*
X351716Y-625554D01*
Y-620619D01*
G01Y-621459D02*
X351403Y-621039D01*
X350933Y-620724D01*
X350384Y-620619D01*
X349758Y-620829D01*
X349366Y-621249D01*
X349053Y-621984D01*
X348896Y-622719D01*
X348974Y-623349D01*
X349288Y-624084D01*
X349758Y-624609D01*
X350384Y-624819D01*
X350854Y-624714D01*
X351403Y-624294D01*
X351716Y-623874D01*
G01X355431Y-621984D02*
X357938D01*
X357703Y-621249D01*
X357311Y-620829D01*
X356763Y-620619D01*
X356214Y-620724D01*
X355744Y-621039D01*
X355431Y-621774D01*
X355274Y-622404D01*
Y-623034D01*
X355431Y-623664D01*
X355823Y-624294D01*
X356293Y-624714D01*
X356841Y-624819D01*
X357389Y-624609D01*
X357938Y-623979D01*
G01X360556Y-624819D02*
Y-620619D01*
G01Y-621774D02*
X360791Y-621249D01*
X361183Y-620829D01*
X361731Y-620619D01*
X362279Y-620829D01*
X362671Y-621249D01*
X362906Y-621774D01*
Y-624819D01*
G01Y-621774D02*
X363141Y-621249D01*
X363533Y-620829D01*
X364081Y-620619D01*
X364629Y-620829D01*
X365021Y-621249D01*
X365256Y-621879D01*
Y-624819D01*
G01X368031Y-621984D02*
X370538D01*
X370303Y-621249D01*
X369911Y-620829D01*
X369363Y-620619D01*
X368814Y-620724D01*
X368344Y-621039D01*
X368031Y-621774D01*
X367874Y-622404D01*
Y-623034D01*
X368031Y-623664D01*
X368423Y-624294D01*
X368893Y-624714D01*
X369441Y-624819D01*
X369989Y-624609D01*
X370538Y-623979D01*
G01X374174Y-624819D02*
Y-620619D01*
G01Y-621669D02*
X374488Y-621144D01*
X374958Y-620724D01*
X375584Y-620619D01*
X376133Y-620724D01*
X376603Y-621144D01*
X376838Y-621879D01*
Y-624819D01*
G01X381806Y-618519D02*
Y-624819D01*
G01X380709Y-620619D02*
X382903D01*
G01X385756Y-626919D02*
X390456D01*
G01X395033Y-621459D02*
X395346Y-621144D01*
X395581Y-620619D01*
X395738Y-619884D01*
X395581Y-619254D01*
X395268Y-618834D01*
X394719Y-618519D01*
X392604D01*
Y-624819D01*
X395189D01*
X395738Y-624399D01*
X396051Y-623769D01*
X396208Y-623034D01*
X396051Y-622299D01*
X395581Y-621669D01*
X395033Y-621459D01*
X392604D01*
G01X398983Y-624819D02*
Y-618519D01*
X400549D01*
X401176Y-618834D01*
X401646Y-619254D01*
X402038Y-619884D01*
X402351Y-620619D01*
X402429Y-621669D01*
X402351Y-622719D01*
X402038Y-623454D01*
X401646Y-624084D01*
X401176Y-624504D01*
X400549Y-624819D01*
X398983D01*
G01X367693Y-679936D02*
Y-671936D01*
X366493Y-673536D01*
G01Y-679936D02*
X368893D01*
G01X373793Y-676603D02*
X374493Y-675669D01*
X375093Y-675136D01*
X375893Y-674869D01*
X376593Y-675136D01*
X377093Y-675669D01*
X377493Y-676469D01*
X377593Y-677403D01*
X377493Y-678203D01*
X377093Y-679003D01*
X376493Y-679669D01*
X375793Y-679936D01*
X374993Y-679669D01*
X374293Y-678870D01*
X373893Y-677669D01*
X373793Y-676336D01*
X373993Y-674603D01*
X374293Y-673669D01*
X374793Y-672736D01*
X375493Y-672069D01*
X376193Y-671936D01*
X376893Y-672203D01*
X377393Y-672869D01*
G01X383693Y-680203D02*
X383493Y-680069D01*
Y-679803D01*
X383693Y-679669D01*
X383893Y-679803D01*
Y-680069D01*
X383693Y-680203D01*
G01X389793Y-676603D02*
X390493Y-675669D01*
X391093Y-675136D01*
X391893Y-674869D01*
X392593Y-675136D01*
X393093Y-675669D01*
X393493Y-676469D01*
X393593Y-677403D01*
X393493Y-678203D01*
X393093Y-679003D01*
X392493Y-679669D01*
X391793Y-679936D01*
X390993Y-679669D01*
X390293Y-678870D01*
X389893Y-677669D01*
X389793Y-676336D01*
X389993Y-674603D01*
X390293Y-673669D01*
X390793Y-672736D01*
X391493Y-672069D01*
X392193Y-671936D01*
X392893Y-672203D01*
X393393Y-672869D01*
G01X412693Y-679936D02*
Y-671936D01*
X411493Y-673536D01*
G01Y-679936D02*
X413893D01*
G01X420493D02*
X420693Y-678203D01*
X420993Y-676736D01*
X421393Y-675403D01*
X421893Y-673936D01*
X422693Y-671936D01*
X418693D01*
G01X428693Y-680203D02*
X428493Y-680069D01*
Y-679803D01*
X428693Y-679669D01*
X428893Y-679803D01*
Y-680069D01*
X428693Y-680203D01*
G01X434793Y-673269D02*
X435393Y-672469D01*
X436093Y-672069D01*
X436893Y-671936D01*
X437893Y-672203D01*
X438593Y-672869D01*
X438793Y-673669D01*
X438693Y-674470D01*
X438293Y-675136D01*
X436293Y-676469D01*
X435393Y-677403D01*
X434793Y-678736D01*
X434593Y-679936D01*
X438793D01*
G01X432493Y-654936D02*
Y-646936D01*
X434493D01*
X435293Y-647336D01*
X435893Y-647869D01*
X436393Y-648669D01*
X436793Y-649603D01*
X436893Y-650936D01*
X436793Y-652269D01*
X436393Y-653203D01*
X435893Y-654003D01*
X435293Y-654536D01*
X434493Y-654936D01*
X432493D01*
G54D15*
X24016Y89331D03*
X330315D03*
G54D117*
X317580Y67941D03*
Y73059D03*
X325020D03*
Y70500D03*
Y67941D03*
G54D24*
X18609Y422600D03*
X32191D03*
G54D51*
X47760Y226076D03*
Y235524D03*
X55240Y226076D03*
X51500D03*
X55240Y235524D03*
X297760Y320382D03*
Y330618D03*
X301500D03*
X305240Y320382D03*
Y330618D03*
G54D108*
X197012Y299320D03*
Y301880D03*
X210988D03*
Y299320D03*
G54D33*
X33306Y196771D03*
Y195196D03*
Y193621D03*
Y192047D03*
Y201495D03*
Y199921D03*
Y198346D03*
G54D42*
X28255Y272190D03*
Y295220D03*
X83341Y87348D03*
Y110378D03*
X324605Y245210D03*
Y268240D03*
G54D60*
X65945Y297776D03*
G54D43*
X26768Y258807D03*
G54D70*
X72410Y141603D03*
X79890D03*
X72410Y149088D03*
X79890D03*
X144260Y209000D03*
X151740D03*
X318134Y300232D03*
Y307682D03*
X327760Y118500D03*
X325614Y300232D03*
Y307682D03*
X335240Y118500D03*
G54D25*
X22638Y27520D03*
X40354D03*
X269095Y29095D03*
X286811D03*
X313977Y27520D03*
X331693D03*
G54D16*
X10470Y71500D03*
X12100Y438790D03*
X104000Y157600D03*
X269600Y337700D03*
X310800Y42000D03*
X323200Y451500D03*
G54D34*
X20500Y211000D03*
X27500D03*
X20500Y218000D03*
X27500D03*
X25000Y240500D03*
X32000D03*
X25000Y233500D03*
X32000D03*
X207750Y361100D03*
X199750D03*
X207595Y378154D03*
X199595D03*
X203750Y369900D03*
X203595Y386954D03*
G54D109*
X203211Y316159D03*
Y311041D03*
X210789Y316159D03*
Y313600D03*
Y311041D03*
G54D118*
X329290Y126103D03*
X321416D03*
Y138309D03*
X329290D03*
X327322Y126103D03*
X325353D03*
X323384D03*
Y138309D03*
X325353D03*
X327322D03*
G54D52*
X36414Y256051D03*
G54D61*
X64567Y315493D03*
X146063D03*
G54D17*
X19500Y121603D03*
Y129083D03*
X18037Y311599D03*
Y304119D03*
X28000Y121603D03*
Y129083D03*
X34839Y311551D03*
Y304071D03*
X26438Y311575D03*
Y304095D03*
X36500Y121603D03*
X45000D03*
X36500Y129083D03*
X45000D03*
X43240Y311757D03*
Y304277D03*
X131000Y210260D03*
Y217740D03*
X220100Y80860D03*
Y88340D03*
X305320Y228803D03*
X313721Y228779D03*
X305320Y236283D03*
X313721Y236259D03*
X322122Y228755D03*
X330523Y228731D03*
X322122Y236235D03*
X330523Y236211D03*
X336500Y132260D03*
Y139740D03*
G54D26*
X27300Y68200D03*
X340639Y432809D03*
G54D80*
X98976Y415200D03*
X108424D03*
G54D35*
X24100Y226000D03*
X29900D03*
X40915Y225958D03*
X35115D03*
X112300Y112300D03*
X118100D03*
X112300Y118500D03*
X118100D03*
X112300Y128500D03*
X118100D03*
X253508Y263492D03*
X247708D03*
X291380Y138297D03*
X297180D03*
X294009Y147731D03*
X288209D03*
G54D71*
X71369Y163879D03*
X68810D03*
X66251D03*
Y172541D03*
X71369D03*
G54D53*
X36414Y254083D03*
G54D119*
X325353Y132206D03*
G54D44*
X23100Y264300D03*
X38101Y239700D03*
X108000Y237200D03*
G54D62*
G01X0Y7874D02*
G03X7874Y0I7874J0D01*
G01X0Y319882D02*
Y7874D01*
G01X984Y320866D02*
G03X0Y319882I0J-984D01*
G01X8858Y320866D02*
X984D01*
G01Y334646D02*
X8858D01*
G01X0Y335630D02*
G03X984Y334646I984J0D01*
G01X0Y442126D02*
Y335630D01*
G01X7874Y450000D02*
G03X0Y442126I0J-7874D01*
G01X7874Y0D02*
X346457D01*
G01X10827Y322835D02*
G02X8858Y320866I-1969J0D01*
G01X10827Y332677D02*
Y322835D01*
G01X8858Y334646D02*
G02X10827Y332677I0J-1969D01*
G01X17717Y450000D02*
X7874D01*
G01X19685Y451969D02*
G02X17717Y450000I-1969J0D01*
G01X19685Y469024D02*
Y451969D01*
G01X22567Y474016D02*
X19685Y469024D01*
G01X39429Y474016D02*
X22567D01*
G01X44350Y450000D02*
G02X42382Y451969I0J1969D01*
G01X50256Y450000D02*
X44350D01*
G01X42382Y451969D02*
Y471063D01*
G01D02*
X39429Y474016D01*
G01X52224Y451969D02*
G02X50256Y450000I-1969J0D01*
G01X52224Y471063D02*
Y451969D01*
G01X55177Y474016D02*
X52224Y471063D01*
G01X121555Y474016D02*
X55177D01*
G01X124508Y471063D02*
X121555Y474016D01*
G01X135335Y451870D02*
G02X124508I-5413J0D01*
G01D02*
Y471063D01*
G01X135335D02*
Y451870D01*
G01X138287Y474016D02*
X135335Y471063D01*
G01X171594Y474016D02*
X138287D01*
G01X174547Y450098D02*
Y471063D01*
G01X181831Y450098D02*
G02X174547I-3642J0D01*
G01X181831Y471063D02*
Y450098D01*
G01X174547Y471063D02*
X171594Y474016D01*
G01X184783D02*
X181831Y471063D01*
G01X251122Y474016D02*
X184783D01*
G01X262933Y450886D02*
G02X254075I-4429J0D01*
G01D02*
Y471063D01*
G01D02*
X251122Y474016D01*
G01X262933Y471063D02*
Y450886D01*
G01X265886Y474016D02*
X262933Y471063D01*
G01X299173Y474016D02*
X265886D01*
G01X304094Y450000D02*
G02X302126Y451969I1J1969D01*
G01D02*
Y471063D01*
G01D02*
X299173Y474016D01*
G01X310000Y450000D02*
X304094D01*
G01X311969Y451969D02*
G02X310000Y450000I-1969J0D01*
G01X311969Y471063D02*
Y451969D01*
G01X314921Y474016D02*
X311969Y471063D01*
G01X331764Y474016D02*
X314921D01*
G01X334646Y469024D02*
X331764Y474016D01*
G01X346457Y0D02*
G03X354331Y7874I0J7874D01*
G01X343504Y322835D02*
Y332677D01*
G01X345472Y320866D02*
G02X343504Y322835I0J1968D01*
G01X353346Y320866D02*
X345472D01*
G01Y334646D02*
X353346D01*
G01X343504Y332677D02*
G02X345472Y334646I1968J0D01*
G01X336614Y450000D02*
G02X334646Y451969I0J1969D01*
G01X346457Y450000D02*
X336614D01*
G01X354331Y442126D02*
G03X346457Y450000I-7874J0D01*
G01X334646Y451969D02*
Y469024D01*
G01X354331Y7874D02*
Y319882D01*
G01D02*
G03X353346Y320866I-984J0D01*
G01X354331Y335630D02*
Y442126D01*
G01X353346Y334646D02*
G03X354331Y335630I1J984D01*
X60864Y344831D03*
Y360579D03*
Y357429D03*
Y354280D03*
Y351130D03*
Y347981D03*
Y376327D03*
Y373177D03*
Y370028D03*
Y366878D03*
Y363729D03*
Y388925D03*
Y385776D03*
Y382626D03*
Y379477D03*
Y392075D03*
X64014Y344831D03*
X67163D03*
X70313D03*
X73462D03*
X76612D03*
X64014Y360579D03*
X67163D03*
X70313D03*
X73462D03*
X76612D03*
X64014Y357429D03*
X67163D03*
X70313D03*
X73462D03*
X76612D03*
X64014Y354280D03*
X67163D03*
X70313D03*
X73462D03*
X76612D03*
X64014Y351130D03*
X67163D03*
X70313D03*
X73462D03*
X76612D03*
X64014Y347981D03*
X67163D03*
X70313D03*
X73462D03*
X76612D03*
X64014Y376327D03*
X67163D03*
X70313D03*
X73462D03*
X76612D03*
X64014Y373177D03*
X67163D03*
X70313D03*
X73462D03*
X76612D03*
X64014Y370028D03*
X67163D03*
X70313D03*
X73462D03*
X76612D03*
X64014Y366878D03*
X67163D03*
X70313D03*
X73462D03*
X76612D03*
X64014Y363729D03*
X67163D03*
X70313D03*
X73462D03*
X76612D03*
X64014Y388925D03*
X67163D03*
X70313D03*
X73462D03*
X76612D03*
X64014Y385776D03*
X67163D03*
X70313D03*
X73462D03*
X76612D03*
X64014Y382626D03*
X67163D03*
X70313D03*
X73462D03*
X76612D03*
X64014Y379477D03*
X67163D03*
X70313D03*
X73462D03*
X76612D03*
X64014Y392075D03*
X67163D03*
X70313D03*
X73462D03*
X76612D03*
X79762Y344831D03*
X82911D03*
X86061D03*
X89210D03*
X92360D03*
X79762Y360579D03*
X82911D03*
X86061D03*
X89210D03*
X92360D03*
X79762Y357429D03*
X82911D03*
X86061D03*
X89210D03*
X92360D03*
X79762Y354280D03*
X82911D03*
X86061D03*
X89210D03*
X92360D03*
X79762Y351130D03*
X82911D03*
X86061D03*
X89210D03*
X92360D03*
X79762Y347981D03*
X82911D03*
X86061D03*
X89210D03*
X92360D03*
X79762Y376327D03*
X82911D03*
X86061D03*
X89210D03*
X92360D03*
X79762Y373177D03*
X82911D03*
X86061D03*
X89210D03*
X92360D03*
X79762Y370028D03*
X82911D03*
X86061D03*
X89210D03*
X92360D03*
X79762Y366878D03*
X82911D03*
X86061D03*
X89210D03*
X92360D03*
X79762Y363729D03*
X82911D03*
X86061D03*
X89210D03*
X92360D03*
X79762Y388925D03*
X82911D03*
X86061D03*
X89210D03*
X92360D03*
X79762Y385776D03*
X82911D03*
X86061D03*
X89210D03*
X92360D03*
X79762Y382626D03*
X82911D03*
X86061D03*
X89210D03*
X92360D03*
X79762Y379477D03*
X82911D03*
X86061D03*
X89210D03*
X92360D03*
X79762Y392075D03*
X82911D03*
X86061D03*
X89210D03*
X92360D03*
X95510Y344831D03*
X98659D03*
X101809D03*
X104958D03*
X108108D03*
X95510Y360579D03*
X98659D03*
X101809D03*
X104958D03*
X108108D03*
X95510Y357429D03*
X98659D03*
X101809D03*
X104958D03*
X108108D03*
X95510Y354280D03*
X98659D03*
X101809D03*
X104958D03*
X108108D03*
X95510Y351130D03*
X98659D03*
X101809D03*
X104958D03*
X108108D03*
X95510Y347981D03*
X98659D03*
X101809D03*
X104958D03*
X108108D03*
X95510Y376327D03*
X98659D03*
X101809D03*
X104958D03*
X108108D03*
X95510Y373177D03*
X98659D03*
X101809D03*
X104958D03*
X108108D03*
X95510Y370028D03*
X98659D03*
X101809D03*
X104958D03*
X108108D03*
X95510Y366878D03*
X98659D03*
X101809D03*
X104958D03*
X108108D03*
X95510Y363729D03*
X98659D03*
X101809D03*
X104958D03*
X108108D03*
X95510Y388925D03*
X98659D03*
X101809D03*
X104958D03*
X108108D03*
X95510Y385776D03*
X98659D03*
X101809D03*
X104958D03*
X108108D03*
X95510Y382626D03*
X98659D03*
X101809D03*
X104958D03*
X108108D03*
X95510Y379477D03*
X98659D03*
X101809D03*
X104958D03*
X108108D03*
X95510Y392075D03*
X98659D03*
X101809D03*
X104958D03*
X108108D03*
X176752Y167603D03*
X179902D03*
X176752Y164454D03*
X179902D03*
X176752Y161304D03*
X179902D03*
X176752Y158155D03*
X179902D03*
X176752Y155005D03*
X179902D03*
X176752Y180202D03*
X179902D03*
X176752Y177052D03*
X179902D03*
X176752Y173903D03*
X179902D03*
X176752Y170753D03*
X179902D03*
X176752Y195950D03*
X179902D03*
X176752Y192800D03*
X179902D03*
X176752Y189651D03*
X179902D03*
X176752Y186501D03*
X179902D03*
X176752Y183351D03*
X179902D03*
X176752Y211698D03*
X179902D03*
X176752Y208548D03*
X179902D03*
X176752Y205399D03*
X179902D03*
X176752Y202249D03*
X179902D03*
X176752Y199099D03*
X179902D03*
X176752Y227446D03*
X179902D03*
X176752Y224296D03*
X179902D03*
X176752Y221147D03*
X179902D03*
X176752Y217997D03*
X179902D03*
X176752Y214847D03*
X179902D03*
X176752Y233745D03*
X179902D03*
X176752Y230595D03*
X179902D03*
X183051Y167603D03*
X186201D03*
X189350D03*
X192500D03*
X195650D03*
X183051Y164454D03*
X186201D03*
X189350D03*
X192500D03*
X195650D03*
X183051Y161304D03*
X186201D03*
X189350D03*
X192500D03*
X195650D03*
X183051Y158155D03*
X186201D03*
X189350D03*
X192500D03*
X195650D03*
X183051Y155005D03*
X186201D03*
X189350D03*
X192500D03*
X195650D03*
X183051Y180202D03*
X186201D03*
X189350D03*
X192500D03*
X183051Y177052D03*
X186201D03*
X189350D03*
X192500D03*
X183051Y173903D03*
X186201D03*
X189350D03*
X192500D03*
X183051Y170753D03*
X186201D03*
X189350D03*
X192500D03*
X195650D03*
X183051Y195950D03*
X186201D03*
X189350D03*
X192500D03*
X183051Y192800D03*
X186201D03*
X189350D03*
X192500D03*
X183051Y189651D03*
X186201D03*
X189350D03*
X192500D03*
X183051Y186501D03*
X186201D03*
X189350D03*
X192500D03*
X183051Y183351D03*
X186201D03*
X189350D03*
X192500D03*
X183051Y211698D03*
X186201D03*
X189350D03*
X192500D03*
X183051Y208548D03*
X186201D03*
X189350D03*
X192500D03*
X183051Y205399D03*
X186201D03*
X189350D03*
X192500D03*
X183051Y202249D03*
X186201D03*
X189350D03*
X192500D03*
X183051Y199099D03*
X186201D03*
X189350D03*
X192500D03*
X183051Y227446D03*
X186201D03*
X189350D03*
X192500D03*
X195650D03*
X183051Y224296D03*
X186201D03*
X189350D03*
X192500D03*
X195650D03*
X183051Y221147D03*
X186201D03*
X189350D03*
X192500D03*
X195650D03*
X183051Y217997D03*
X186201D03*
X189350D03*
X192500D03*
X195650D03*
X183051Y214847D03*
X186201D03*
X189350D03*
X192500D03*
X183051Y233745D03*
X186201D03*
X189350D03*
X192500D03*
X195650D03*
X183051Y230595D03*
X186201D03*
X189350D03*
X192500D03*
X195650D03*
X198799Y167603D03*
X201949D03*
X205098D03*
X208248D03*
X211398D03*
X198799Y164454D03*
X201949D03*
X205098D03*
X208248D03*
X211398D03*
X198799Y161304D03*
X201949D03*
X205098D03*
X208248D03*
X211398D03*
X198799Y158155D03*
X201949D03*
X205098D03*
X208248D03*
X211398D03*
X198799Y155005D03*
X201949D03*
X205098D03*
X208248D03*
X211398D03*
X198799Y180202D03*
X201949D03*
X205098D03*
X208248D03*
X211398D03*
X198799Y177052D03*
X201949D03*
X205098D03*
X208248D03*
X211398D03*
X198799Y170753D03*
X201949D03*
X205098D03*
X208248D03*
X211398D03*
X198799Y195950D03*
X201949D03*
X205098D03*
X208248D03*
X211398D03*
X198799Y192800D03*
X201949D03*
X205098D03*
X208248D03*
X211398D03*
X198799Y189651D03*
X201949D03*
X205098D03*
X208248D03*
X211398D03*
X198799Y186501D03*
X201949D03*
X205098D03*
X208248D03*
X211398D03*
X198799Y183351D03*
X201949D03*
X205098D03*
X208248D03*
X211398D03*
X198799Y211698D03*
X201949D03*
X205098D03*
X208248D03*
X211398D03*
X198799Y208548D03*
X201949D03*
X205098D03*
X208248D03*
X211398D03*
X198799Y205399D03*
X201949D03*
X205098D03*
X208248D03*
X211398D03*
X198799Y202249D03*
X201949D03*
X205098D03*
X208248D03*
X211398D03*
X198799Y199099D03*
X201949D03*
X205098D03*
X208248D03*
X211398D03*
X198799Y227446D03*
X201949D03*
X205098D03*
X208248D03*
X211398D03*
X198799Y224296D03*
X201949D03*
X205098D03*
X208248D03*
X211398D03*
X198799Y221147D03*
X201949D03*
X205098D03*
X208248D03*
X211398D03*
X198799Y217997D03*
X201949D03*
X205098D03*
X208248D03*
X211398D03*
X198799Y233745D03*
X201949D03*
X205098D03*
X208248D03*
X211398D03*
X198799Y230595D03*
X201949D03*
X205098D03*
X208248D03*
X211398D03*
X214547Y167603D03*
X217697D03*
X220846D03*
X223996D03*
X227146D03*
X214547Y164454D03*
X217697D03*
X220846D03*
X223996D03*
X227146D03*
X214547Y161304D03*
X217697D03*
X220846D03*
X223996D03*
X227146D03*
X214547Y158155D03*
X217697D03*
X220846D03*
X223996D03*
X227146D03*
X214547Y155005D03*
X217697D03*
X220846D03*
X223996D03*
X227146D03*
X214547Y180202D03*
X217697D03*
X220846D03*
X223996D03*
X227146D03*
X214547Y177052D03*
X217697D03*
X220846D03*
X223996D03*
X227146D03*
X214547Y170753D03*
X217697D03*
X220846D03*
X223996D03*
X227146D03*
X214547Y195950D03*
X217697D03*
X220846D03*
X223996D03*
X227146D03*
X214547Y192800D03*
X217697D03*
X220846D03*
X223996D03*
X227146D03*
X214547Y189651D03*
X217697D03*
X220846D03*
X223996D03*
X227146D03*
X214547Y186501D03*
X217697D03*
X220846D03*
X223996D03*
X227146D03*
X214547Y183351D03*
X217697D03*
X220846D03*
X223996D03*
X227146D03*
X214547Y211698D03*
X217697D03*
X220846D03*
X223996D03*
X227146D03*
X214547Y208548D03*
X217697D03*
X220846D03*
X223996D03*
X227146D03*
X214547Y205399D03*
X217697D03*
X220846D03*
X223996D03*
X227146D03*
X214547Y202249D03*
X217697D03*
X220846D03*
X223996D03*
X227146D03*
X214547Y199099D03*
X217697D03*
X220846D03*
X223996D03*
X227146D03*
X214547Y227446D03*
X217697D03*
X220846D03*
X223996D03*
X227146D03*
X214547Y224296D03*
X217697D03*
X220846D03*
X223996D03*
X227146D03*
X214547Y221147D03*
X217697D03*
X220846D03*
X223996D03*
X227146D03*
X214547Y217997D03*
X217697D03*
X220846D03*
X223996D03*
X227146D03*
X214547Y233745D03*
X217697D03*
X220846D03*
X223996D03*
X227146D03*
X214547Y230595D03*
X217697D03*
X220846D03*
X223996D03*
X227146D03*
X230295Y167603D03*
X233445D03*
X236594D03*
X239744D03*
X230295Y164454D03*
X233445D03*
X236594D03*
X239744D03*
X230295Y161304D03*
X233445D03*
X236594D03*
X239744D03*
X230295Y158155D03*
X233445D03*
X236594D03*
X239744D03*
X230295Y155005D03*
X233445D03*
X236594D03*
X239744D03*
X230295Y180202D03*
X233445D03*
X239744D03*
X230295Y177052D03*
X233445D03*
X239744D03*
Y173903D03*
X230295Y170753D03*
X233445D03*
X236594D03*
X239744D03*
X230295Y195950D03*
X233445D03*
X239744D03*
X230295Y192800D03*
X233445D03*
X239744D03*
X230295Y189651D03*
X233445D03*
X239744D03*
X230295Y186501D03*
X233445D03*
X239744D03*
X230295Y183351D03*
X233445D03*
X239744D03*
X230295Y211698D03*
X233445D03*
X239744D03*
X230295Y208548D03*
X233445D03*
X239744D03*
X230295Y205399D03*
X233445D03*
X239744D03*
X230295Y202249D03*
X233445D03*
X239744D03*
X230295Y199099D03*
X233445D03*
X239744D03*
X230295Y227446D03*
X233445D03*
X236594D03*
X239744D03*
X230295Y224296D03*
X233445D03*
X236594D03*
X239744D03*
X230295Y221147D03*
X233445D03*
X236594D03*
X239744D03*
X230295Y217997D03*
X233445D03*
X236594D03*
X239744D03*
Y214847D03*
X230295Y233745D03*
X233445D03*
X236594D03*
X239744D03*
X230295Y230595D03*
X233445D03*
X236594D03*
X239744D03*
X242894Y167603D03*
X246043D03*
X249193D03*
X252342D03*
X255492D03*
X242894Y164454D03*
X246043D03*
X249193D03*
X252342D03*
X255492D03*
X242894Y161304D03*
X246043D03*
X249193D03*
X252342D03*
X255492D03*
X242894Y158155D03*
X246043D03*
X249193D03*
X252342D03*
X255492D03*
X242894Y155005D03*
X246043D03*
X249193D03*
X252342D03*
X255492D03*
X242894Y180202D03*
X246043D03*
X249193D03*
X252342D03*
X255492D03*
X242894Y177052D03*
X246043D03*
X249193D03*
X252342D03*
X255492D03*
X242894Y173903D03*
X246043D03*
X249193D03*
X252342D03*
X255492D03*
X242894Y170753D03*
X246043D03*
X249193D03*
X252342D03*
X255492D03*
X242894Y195950D03*
X246043D03*
X249193D03*
X252342D03*
X255492D03*
X242894Y192800D03*
X246043D03*
X249193D03*
X252342D03*
X255492D03*
X242894Y189651D03*
X246043D03*
X249193D03*
X252342D03*
X255492D03*
X242894Y186501D03*
X246043D03*
X249193D03*
X252342D03*
X255492D03*
X242894Y183351D03*
X246043D03*
X249193D03*
X252342D03*
X255492D03*
X242894Y211698D03*
X246043D03*
X249193D03*
X252342D03*
X255492D03*
X242894Y208548D03*
X246043D03*
X249193D03*
X252342D03*
X255492D03*
X242894Y205399D03*
X246043D03*
X249193D03*
X252342D03*
X255492D03*
X242894Y202249D03*
X246043D03*
X249193D03*
X252342D03*
X255492D03*
X242894Y199099D03*
X246043D03*
X249193D03*
X252342D03*
X255492D03*
X242894Y227446D03*
X246043D03*
X249193D03*
X252342D03*
X255492D03*
X242894Y224296D03*
X246043D03*
X249193D03*
X252342D03*
X255492D03*
X242894Y221147D03*
X246043D03*
X249193D03*
X252342D03*
X255492D03*
X242894Y217997D03*
X246043D03*
X249193D03*
X252342D03*
X255492D03*
X242894Y214847D03*
X246043D03*
X249193D03*
X252342D03*
X255492D03*
X242894Y233745D03*
X246043D03*
X249193D03*
X252342D03*
X255492D03*
X242894Y230595D03*
X246043D03*
X249193D03*
X252342D03*
X255492D03*
G54D36*
X30148Y246113D03*
X30783Y264500D03*
X28183Y316900D03*
X19883Y328600D03*
X39983Y38000D03*
X45467Y214718D03*
X36783Y214700D03*
X46583Y241000D03*
X47383Y248800D03*
X39475Y246116D03*
X46583Y244900D03*
X37783Y264500D03*
X53699Y38500D03*
X54633Y211200D03*
X51783Y260800D03*
X49983Y328000D03*
Y324000D03*
Y344000D03*
Y348000D03*
Y364000D03*
Y368000D03*
Y372000D03*
Y376000D03*
Y380000D03*
Y384000D03*
X50383Y394350D03*
X66458Y116450D03*
X77502Y135866D03*
X81049Y118216D03*
X94473Y428020D03*
X118083Y102000D03*
Y107600D03*
X110983Y102000D03*
Y107500D03*
X117483Y123500D03*
X121783Y346400D03*
Y342500D03*
X118983Y415000D03*
X130483Y50000D03*
X136983Y201500D03*
X133483Y253700D03*
X132683Y261900D03*
X136083Y429000D03*
X152483Y142000D03*
X143483Y175200D03*
X143493Y179160D03*
X151577Y182594D03*
X139883Y348300D03*
Y351900D03*
X149563Y419250D03*
X166283Y112800D03*
X159388Y153077D03*
X158592Y182644D03*
X158699Y178679D03*
X158683Y174800D03*
X158733Y187354D03*
X158783Y191700D03*
X159483Y224000D03*
X158282Y313560D03*
X158283Y309700D03*
X160983Y350500D03*
X153483Y429000D03*
X174383Y272800D03*
X185983Y88000D03*
Y92000D03*
X189983Y267000D03*
X196983Y264810D03*
X187583Y294500D03*
X192183Y311100D03*
X210623Y244900D03*
X209783Y419600D03*
X217403Y102014D03*
X225103Y258930D03*
X225983Y296600D03*
Y300600D03*
X220883Y416000D03*
X236283Y319400D03*
X257283Y98600D03*
Y95100D03*
X255083Y110300D03*
X269944Y368610D03*
Y381075D03*
X284193Y93260D03*
X276703Y99350D03*
X286041Y138403D03*
X297483Y79500D03*
X291983Y100400D03*
X297743Y142907D03*
X300483Y311500D03*
X293208Y358508D03*
Y363008D03*
X292744Y387500D03*
X305983Y79500D03*
X308364Y273256D03*
X329110Y144423D03*
X324363Y275940D03*
X323142Y294816D03*
X337283Y70000D03*
X337308Y154911D03*
Y164911D03*
Y159911D03*
Y169911D03*
Y179911D03*
Y174911D03*
Y183926D03*
Y189911D03*
X336807Y292085D03*
G54D90*
X137240Y152985D03*
X133500D03*
X129760D03*
X137240Y163615D03*
X133500D03*
X129760D03*
G54D45*
X28260Y322441D03*
Y325000D03*
Y327559D03*
X35740D03*
Y325000D03*
Y322441D03*
G54D72*
X77384Y240085D03*
X75416D03*
X73447D03*
X77384Y250715D03*
X75416D03*
X73447D03*
X79353Y240085D03*
Y250715D03*
X101253Y239985D03*
X99284D03*
X97316D03*
X95347D03*
X101253Y250615D03*
X99284D03*
X97316D03*
X95347D03*
G54D27*
X35256Y140183D03*
Y174347D03*
G54D81*
X113760Y74441D03*
Y77000D03*
X121240D03*
Y74441D03*
X113760Y79559D03*
X121240D03*
X132740Y44459D03*
Y41900D03*
Y39341D03*
X125260D03*
Y41900D03*
Y44459D03*
X253240Y46559D03*
Y44000D03*
Y41441D03*
X245760D03*
Y44000D03*
Y46559D03*
G54D63*
X59303Y421214D03*
Y416096D03*
X51823D03*
Y418655D03*
Y421214D03*
G54D18*
X16608Y190420D03*
X18000Y233084D03*
X42281Y206242D03*
X46307D03*
X40500Y233984D03*
X48440Y255594D03*
X40500Y373984D03*
Y366984D03*
Y380984D03*
Y402484D03*
X48600Y431984D03*
X44700D03*
X52500Y65984D03*
X63918Y126139D03*
X60090Y126144D03*
X61216Y228784D03*
X52440Y255594D03*
X63300Y260784D03*
X49938Y308780D03*
X55800Y330984D03*
X52500Y431984D03*
X56500D03*
X69200Y183784D03*
X65500D03*
X73400Y222684D03*
X77500D03*
X75400Y232884D03*
X65216Y228784D03*
X72500Y261484D03*
X67000Y405984D03*
X71000D03*
X88083Y124956D03*
X81500Y222684D03*
X91500Y272484D03*
X93500Y261984D03*
X86500Y261784D03*
X90804Y333304D03*
X79000Y405984D03*
X102800Y87984D03*
X100000Y95984D03*
X99700Y122084D03*
X95800D03*
X100400Y134984D03*
X96400D03*
X106800Y259584D03*
X99500Y272484D03*
X103500D03*
X95500D03*
X107400Y273384D03*
X103100Y331184D03*
X98000D03*
X98680Y428434D03*
X120500Y41984D03*
X112500D03*
X110800Y260184D03*
X119760Y271185D03*
X115260D03*
X111500Y270984D03*
X114800Y260784D03*
X111100Y279184D03*
X115260Y279185D03*
X119760D03*
X117918Y331472D03*
X113918D03*
X118800Y357184D03*
X129500Y143984D03*
X137525Y143811D03*
X133500Y143984D03*
X133000Y176484D03*
X129000D03*
X126500Y256684D03*
X124500Y264184D03*
X128760Y271185D03*
X124260D03*
X133000Y270984D03*
X124260Y279185D03*
X128760D03*
X129918Y331472D03*
X133918D03*
X141500Y143484D03*
X152434Y153199D03*
X141500Y241484D03*
X145918Y331472D03*
X149918D03*
X139900Y431984D03*
X155300Y104284D03*
X155530Y122104D03*
X164400Y122984D03*
X168000Y137984D03*
X160457Y145493D03*
X156430Y145465D03*
X160500Y205584D03*
X156028Y219703D03*
X157500Y231984D03*
X156973Y252495D03*
X165013D03*
X160713Y260513D03*
X156713D03*
X155000Y292484D03*
X165200Y320484D03*
X161026Y346680D03*
X178000Y107284D03*
X172632Y123010D03*
X168616D03*
X178186Y122710D03*
X180000Y137784D03*
X176000D03*
X178174Y261005D03*
X169026Y346680D03*
X173026D03*
X187272Y81937D03*
X191312D03*
X196065Y123010D03*
X191400D03*
X184000Y137884D03*
X183350Y262264D03*
X188000Y320884D03*
X193750Y363734D03*
Y379484D03*
Y388484D03*
X192334Y432236D03*
X211000Y43984D03*
X200000Y122984D03*
X210189Y123010D03*
X204000Y122984D03*
X199985Y137853D03*
X204120D03*
X207912Y253108D03*
X199810Y253270D03*
X209500Y275984D03*
X199405Y432236D03*
X203400Y432184D03*
X219000Y43984D03*
X214500Y93984D03*
X223300Y122984D03*
X214464Y123010D03*
X218200Y252084D03*
X221800D03*
X222300Y282084D03*
X221260Y313344D03*
X220600Y320984D03*
X226650Y379294D03*
X213500Y379484D03*
X237000Y44484D03*
X233000D03*
X242200Y122984D03*
X228600D03*
X238382Y123010D03*
X233511Y138053D03*
X242195Y137853D03*
X237655D03*
X239100Y253684D03*
X235100D03*
X228500Y334984D03*
Y347784D03*
X246000Y122984D03*
X252400Y280394D03*
X254010Y426698D03*
X265900Y112984D03*
X261300Y253284D03*
X268000Y426784D03*
X286000Y44484D03*
X281500D03*
X286000Y65484D03*
X277000Y78984D03*
X281000D03*
X285000D03*
X285295Y113870D03*
X277300Y108884D03*
X285295Y131451D03*
X277049Y131538D03*
X278028Y140298D03*
X272698Y140308D03*
X284100Y419784D03*
X290245Y44487D03*
X301936Y141256D03*
X288000Y293984D03*
X316066Y113869D03*
X313936Y141356D03*
X309936D03*
X305936D03*
X303077Y294698D03*
X307087D03*
X320872Y120186D03*
X317936Y149356D03*
X322000Y147984D03*
X333278Y148348D03*
X333839Y278881D03*
X333828Y286261D03*
X332500Y303284D03*
X336500D03*
G54D54*
X34642Y251327D03*
G54D37*
X24996Y254083D03*
G54D55*
X34642Y258807D03*
G54D64*
X58839Y465590D03*
X61201D03*
X65925D03*
X73012D03*
X68287D03*
X75374D03*
X80098D03*
X87185D03*
X82461D03*
X89547D03*
X94272D03*
X101358D03*
X108445D03*
X96634D03*
X103721D03*
X115532D03*
X110807D03*
X117894D03*
X144311D03*
X151398D03*
X146673D03*
X158484D03*
X165571D03*
X153760D03*
X160846D03*
X167933D03*
X188445D03*
X195532D03*
X190807D03*
X202618D03*
X209705D03*
X197894D03*
X204980D03*
X212067D03*
X216791D03*
X219154D03*
X223878D03*
X226240D03*
X228602D03*
X230965D03*
X233327D03*
X235689D03*
X238051D03*
X240413D03*
X242776D03*
X245138D03*
X247500D03*
X249862D03*
X271890D03*
X274252D03*
G54D82*
X121095Y68911D03*
X128575Y61037D03*
Y68911D03*
X293630Y84000D03*
X297370D03*
X303130D03*
X306870D03*
G54D73*
X69750Y271100D03*
Y276900D03*
X80500Y161400D03*
Y155600D03*
X326000Y314100D03*
Y319900D03*
G54D91*
X138261Y216285D03*
Y224159D03*
Y218253D03*
Y220222D03*
Y222191D03*
X150467Y224159D03*
Y216285D03*
Y222191D03*
Y220222D03*
Y218253D03*
G54D28*
X32914Y184247D03*
X21209Y259777D03*
X46984Y38000D03*
X45070Y58317D03*
X47203Y187525D03*
X45370Y191535D03*
X40233Y184311D03*
X45468Y210701D03*
X44388Y259638D03*
X39884Y317100D03*
X37984Y338000D03*
X40984Y348500D03*
Y352000D03*
X44484Y415700D03*
Y419700D03*
X37584Y411900D03*
Y415700D03*
X53700Y34873D03*
X54884Y220600D03*
X51784Y264600D03*
X49984Y332000D03*
Y336000D03*
Y340000D03*
Y387700D03*
X50384Y397850D03*
Y401350D03*
X92984Y255500D03*
X79484Y259200D03*
X92734Y417000D03*
Y412500D03*
X107484Y80000D03*
X112785Y62963D03*
Y66963D03*
X121784Y350300D03*
X129484Y54300D03*
X126484Y114000D03*
Y131000D03*
X150560Y187354D03*
X158884Y158300D03*
X158584Y163400D03*
X159184Y167100D03*
X158684Y171000D03*
X157284Y195700D03*
X159841Y212568D03*
X155924Y242750D03*
X158284Y301000D03*
Y297000D03*
Y305100D03*
X153584Y432600D03*
X180884Y272800D03*
X178984Y325200D03*
Y329200D03*
X177484Y432600D03*
X185984Y96000D03*
X195284Y111300D03*
X197054Y260830D03*
X186384Y300200D03*
Y304200D03*
X199584Y268700D03*
X205484Y273000D03*
X217404Y97984D03*
X225984Y304600D03*
X226624Y372400D03*
X226614Y383260D03*
X232684Y258200D03*
X249932Y257365D03*
X253297Y268403D03*
X243488Y313514D03*
X250484Y313500D03*
X243488Y319310D03*
X250484Y322000D03*
X261984Y110300D03*
X261384Y259900D03*
X269945Y364610D03*
Y385343D03*
X280234Y123250D03*
X272984Y399500D03*
X300484Y307000D03*
X291484Y372700D03*
X293209Y367508D03*
X292745Y391600D03*
X303484Y57000D03*
X311284Y134300D03*
X308365Y285092D03*
Y281088D03*
Y277100D03*
X307984Y311500D03*
X319084Y62700D03*
X329111Y148439D03*
X337284Y66000D03*
Y74000D03*
X337544Y125500D03*
X336784Y295900D03*
X332984Y358500D03*
Y376500D03*
Y367500D03*
Y372000D03*
Y363000D03*
Y381000D03*
Y385500D03*
G54D19*
X16608Y187453D03*
X18000Y230117D03*
X42281Y203275D03*
X46307D03*
X40500Y231017D03*
X48440Y252627D03*
X40500Y371017D03*
Y364017D03*
Y378017D03*
Y399517D03*
X48600Y429017D03*
X44700D03*
X52500Y63017D03*
X63918Y123172D03*
X60090Y123177D03*
X61216Y225817D03*
X52440Y252627D03*
X63300Y257817D03*
X49938Y305813D03*
X55800Y328017D03*
X52500Y429017D03*
X56500D03*
X69200Y180817D03*
X65500D03*
X73400Y219717D03*
X77500D03*
X65216Y225817D03*
X75400Y229917D03*
X72500Y258517D03*
X67000Y403017D03*
X71000D03*
X88083Y121989D03*
X81500Y219717D03*
X91500Y269517D03*
X93500Y259017D03*
X86500Y258817D03*
X90804Y330337D03*
X79000Y403017D03*
X102800Y85017D03*
X100000Y93017D03*
X99700Y119117D03*
X95800D03*
X100400Y132017D03*
X96400D03*
X106800Y256617D03*
X99500Y269517D03*
X107400Y270417D03*
X103500Y269517D03*
X95500D03*
X103100Y328217D03*
X98000D03*
X98680Y425467D03*
X120500Y39017D03*
X112500D03*
X110800Y257217D03*
X119760Y268218D03*
X115260D03*
X111500Y268017D03*
X114800Y257817D03*
X111100Y276217D03*
X115260Y276218D03*
X119760D03*
X117918Y328505D03*
X113918D03*
X118800Y354217D03*
X129500Y141017D03*
X137525Y140844D03*
X133500Y141017D03*
X133000Y173517D03*
X129000D03*
X126500Y253717D03*
X124500Y261217D03*
X128760Y268218D03*
X124260D03*
X133000Y268017D03*
X124260Y276218D03*
X128760D03*
X129918Y328505D03*
X133918D03*
X141500Y140517D03*
X152434Y150232D03*
X141500Y238517D03*
X145918Y328505D03*
X149918D03*
X139900Y429017D03*
X155300Y101317D03*
X155530Y119137D03*
X164400Y120017D03*
X168000Y135017D03*
X160457Y142526D03*
X156430Y142498D03*
X160500Y202617D03*
X156028Y216736D03*
X157500Y229017D03*
X156973Y249528D03*
X160713Y257546D03*
X156713D03*
X165013Y249528D03*
X155000Y289517D03*
X165200Y317517D03*
X161026Y343713D03*
X178000Y104317D03*
X172632Y120043D03*
X168616D03*
X178186Y119743D03*
X180000Y134817D03*
X176000D03*
X178174Y258038D03*
X169026Y343713D03*
X173026D03*
X187272Y78970D03*
X191312D03*
X196065Y120043D03*
X191400D03*
X184000Y134917D03*
X183350Y259297D03*
X188000Y317917D03*
X193750Y360767D03*
Y376517D03*
Y385517D03*
X192334Y429269D03*
X211000Y41017D03*
X200000Y120017D03*
X210189Y120043D03*
X204000Y120017D03*
X199985Y134886D03*
X204120D03*
X207912Y250141D03*
X199810Y250303D03*
X209500Y273017D03*
X199405Y429269D03*
X203400Y429217D03*
X219000Y41017D03*
X214500Y91017D03*
X223300Y120017D03*
X214464Y120043D03*
X218200Y249117D03*
X221800D03*
X222300Y279117D03*
X221260Y310377D03*
X220600Y318017D03*
X226650Y376327D03*
X213500Y376517D03*
X237000Y41517D03*
X233000D03*
X242200Y120017D03*
X228600D03*
X238382Y120043D03*
X233511Y135086D03*
X242195Y134886D03*
X237655D03*
X239100Y250717D03*
X235100D03*
X228500Y332017D03*
Y344817D03*
X246000Y120017D03*
X252400Y277427D03*
X254010Y423731D03*
X265900Y110017D03*
X261300Y250317D03*
X268000Y423817D03*
X286000Y41517D03*
X281500D03*
X286000Y62517D03*
X277000Y76017D03*
X281000D03*
X285000D03*
X277300Y105917D03*
X285295Y110903D03*
Y128484D03*
X278028Y137331D03*
X272698Y137341D03*
X277049Y128571D03*
X284100Y416817D03*
X290245Y41520D03*
X301936Y138289D03*
X288000Y291017D03*
X316066Y110902D03*
X313936Y138389D03*
X309936D03*
X305936D03*
X303077Y291731D03*
X307087D03*
X320872Y117219D03*
X317936Y146389D03*
X322000Y145017D03*
X333278Y145381D03*
X333839Y275914D03*
X333828Y283294D03*
X332500Y300317D03*
X336500D03*
G54D46*
X23819Y339154D03*
Y349154D03*
Y359154D03*
Y369154D03*
Y379154D03*
Y389154D03*
Y399154D03*
X65709Y52244D03*
X75709Y42244D03*
Y52244D03*
X95709Y42244D03*
X85709D03*
X95709Y52244D03*
X85709D03*
G54D38*
X24996Y256051D03*
G54D65*
X56476Y466378D03*
X63563D03*
X70650D03*
X77736D03*
X84823D03*
X91909D03*
X98996D03*
X106083D03*
X113169D03*
X120256D03*
X139587D03*
X141949D03*
X149035D03*
X156122D03*
X163209D03*
X170295D03*
X186083D03*
X193169D03*
X200256D03*
X207343D03*
X214429D03*
X221516D03*
X267165D03*
X269528D03*
X276614D03*
X278976D03*
X281339D03*
X283701D03*
X286063D03*
X288425D03*
X290787D03*
X293150D03*
X295512D03*
X297874D03*
G54D74*
X73819Y288821D03*
X71850D03*
X69882D03*
X74803Y318544D03*
X72835D03*
X70866D03*
X68898D03*
X91535Y288821D03*
X89567D03*
X87598D03*
X85630D03*
X83661D03*
X92520Y318544D03*
X90551D03*
X88583D03*
X86614D03*
X84646D03*
X107283Y288821D03*
X105315D03*
X103347D03*
X101378D03*
X99409D03*
X97441D03*
X95472D03*
X93504D03*
X106299Y318544D03*
X104331D03*
X102362D03*
X100394D03*
X98425D03*
X96457D03*
X94488D03*
X123032Y288821D03*
X121063D03*
X119095D03*
X117126D03*
X115158D03*
X113189D03*
X111221D03*
X109252D03*
X122047Y318544D03*
X120079D03*
X118110D03*
X116142D03*
X114173D03*
X112205D03*
X110236D03*
X108268D03*
X136811Y288821D03*
X134843D03*
X132874D03*
X130906D03*
X128937D03*
X126969D03*
X125000D03*
X137795Y318544D03*
X135827D03*
X133858D03*
X131890D03*
X129921D03*
X127953D03*
X125984D03*
X124016D03*
X140748Y288821D03*
X138780D03*
X141732Y318544D03*
X139764D03*
G54D83*
X120300Y85451D03*
X116560D03*
X112820D03*
Y94900D03*
X116560D03*
X120300D03*
X271066Y118077D03*
X263586D03*
Y127525D03*
X267326D03*
X271066D03*
G54D92*
X138013Y365197D03*
Y405749D03*
X153013Y365197D03*
X148013D03*
X143013D03*
Y405749D03*
X148013D03*
X153013D03*
X168013Y365197D03*
X163013D03*
X158013D03*
Y405749D03*
X163013D03*
X168013D03*
X173013Y365197D03*
Y405749D03*
G54D56*
X46925Y360000D03*
X50075D03*
G54D47*
X23819Y409154D03*
X65709Y42244D03*
G54D29*
X22282Y197854D03*
G54D48*
X48038Y45897D03*
X45479D03*
X42920D03*
Y52897D03*
X48038D03*
G54D93*
X138012Y366574D03*
Y404370D03*
X153012Y366574D03*
X148012D03*
X143012D03*
Y404370D03*
X148012D03*
X153012D03*
X168012Y366574D03*
X163012D03*
X158012D03*
Y404370D03*
X163012D03*
X168012D03*
X173012Y366574D03*
Y404370D03*
G54D75*
X74419Y417300D03*
X83081Y421040D03*
Y413560D03*
G54D84*
X123376Y105000D03*
Y122500D03*
G54D39*
X28737Y258413D03*
X32673D03*
X30705D03*
X32673Y251721D03*
X28737D03*
G54D57*
X63898Y24764D03*
X90472D03*
X117047D03*
X211142D03*
X237717D03*
G54D66*
X73898D03*
X100472D03*
X127047D03*
X221142D03*
X247717D03*
G54D76*
X105315Y186571D03*
G54D58*
X59441Y141011D03*
Y148589D03*
X62000D03*
X57141Y197411D03*
X62259D03*
X57141Y204989D03*
X59700D03*
X62259D03*
X64559Y141011D03*
Y148589D03*
X160559Y273711D03*
X158000D03*
X155441D03*
X160559Y281289D03*
X155441D03*
G54D67*
X78031Y123474D03*
X74095D03*
X323795Y282404D03*
X319859D03*
G54D49*
X47059Y64760D03*
X44500D03*
X41941D03*
Y72240D03*
X44500D03*
X47059D03*
G54D85*
X123474Y101063D03*
Y103032D03*
Y106968D03*
Y118563D03*
Y120532D03*
Y108937D03*
Y124468D03*
Y126437D03*
X126526Y106968D03*
Y103032D03*
Y101063D03*
Y120532D03*
Y118563D03*
Y108937D03*
Y126437D03*
Y124468D03*
G54D94*
X153237Y58583D03*
X165048Y52677D03*
X161111Y58583D03*
X168985D03*
X182764Y52677D03*
X172922D03*
X176859Y58583D03*
X184733D03*
G54D59*
X63300Y241363D03*
X60741D03*
Y249237D03*
X63300D03*
X65859Y241363D03*
Y249237D03*
X90059Y241363D03*
X87500D03*
X84941D03*
Y249237D03*
X87500D03*
X90059D03*
G54D77*
X105316Y213343D03*
G54D95*
X146260Y72126D03*
Y129606D03*
G54D68*
X76063Y125049D03*
X74095Y129379D03*
X78031D03*
X321827Y283979D03*
X319859Y288309D03*
X323795D03*
G54D86*
X115359Y242060D03*
X112800D03*
X110241D03*
Y249540D03*
X112800D03*
X115359D03*
G54D87*
X143118Y44803D03*
X194851D03*
G54D78*
X108776Y47760D03*
Y51500D03*
Y55240D03*
X118224Y47760D03*
Y55240D03*
X121882Y61037D03*
X135824Y240260D03*
X126376D03*
X135824Y247740D03*
X126376Y244000D03*
Y247740D03*
G54D69*
X70354Y124261D03*
Y126230D03*
Y128198D03*
Y130167D03*
X81772D03*
Y128198D03*
Y126230D03*
Y124261D03*
X316118Y283191D03*
Y285160D03*
Y287128D03*
Y289097D03*
X327536Y285160D03*
Y283191D03*
Y289097D03*
Y287128D03*
G54D96*
X144364Y220222D03*
G54D88*
X136319Y77244D03*
Y81181D03*
Y85118D03*
Y89055D03*
Y92992D03*
Y96929D03*
Y100866D03*
Y104803D03*
Y108740D03*
Y112677D03*
Y116614D03*
Y120551D03*
Y124488D03*
G54D79*
X107969Y63302D03*
Y66648D03*
X114661Y63302D03*
Y66648D03*
G54D97*
X144685Y297776D03*
G54D89*
X126378Y105000D03*
Y122500D03*
G54D98*
X155205Y52677D03*
G54D99*
X166719Y73224D03*
M02*
